(lib_symbols
	(symbol "antmicroCapacitors0402:C_100n_50V_X8L_0402"
			(pin_numbers
				(hide yes)
			)
			(pin_names
				(hide yes)
			)
			(exclude_from_sim no)
			(in_bom yes)
			(on_board yes)
			(property "Reference" "C"
				(at 15.24 -5.08 0)
				(effects
					(font
						(size 1.27 1.27)
						(thickness 0.15)
					)
					(justify left bottom)
				)
			)
			(property "Value" "C_100n_50V_X8L_0402"
				(at 15.24 -22.86 0)
				(effects
					(font
						(size 1.27 1.27)
						(thickness 0.15)
					)
					(justify left bottom)
					(hide yes)
				)
			)
			(property "Footprint" "antmicro-footprints:C_0402_1005Metric"
				(at 15.24 -25.4 0)
				(effects
					(font
						(size 1.27 1.27)
						(thickness 0.15)
					)
					(justify left bottom)
					(hide yes)
				)
			)
			(property "Datasheet" "https://www.murata.com/products/productdetail?partno=GCM155L8EH104KE07%23"
				(at 15.24 -27.94 0)
				(effects
					(font
						(size 1.27 1.27)
						(thickness 0.15)
					)
					(justify left bottom)
					(hide yes)
				)
			)
			(property "Description" "SMD Multilayer Ceramic Capacitor, 100nF, 50V, 0402, ±10%, X8L"
				(at 0 0 0)
				(effects
					(font
						(size 1.27 1.27)
					)
					(hide yes)
				)
			)
			(property "MPN" "GCM155L8EH104KE07D"
				(at 15.24 -30.48 0)
				(effects
					(font
						(size 1.27 1.27)
						(thickness 0.15)
					)
					(justify left bottom)
					(hide yes)
				)
			)
			(property "Val" "100n"
				(at 15.24 -7.62 0)
				(effects
					(font
						(size 1.27 1.27)
						(thickness 0.15)
					)
					(justify left bottom)
				)
			)
			(property "Voltage" "50V"
				(at 15.24 -10.16 0)
				(effects
					(font
						(size 1.27 1.27)
						(thickness 0.15)
					)
					(justify left bottom)
					(hide yes)
				)
			)
			(property "Dielectric" "X8L"
				(at 15.24 -12.7 0)
				(effects
					(font
						(size 1.27 1.27)
						(thickness 0.15)
					)
					(justify left bottom)
					(hide yes)
				)
			)
			(property "Manufacturer" "Murata"
				(at 15.24 -15.24 0)
				(effects
					(font
						(size 1.27 1.27)
						(thickness 0.15)
					)
					(justify left bottom)
					(hide yes)
				)
			)
			(property "License" "Apache-2.0"
				(at 15.24 -17.78 0)
				(effects
					(font
						(size 1.27 1.27)
						(thickness 0.15)
					)
					(justify left bottom)
					(hide yes)
				)
			)
			(property "Author" "Antmicro"
				(at 15.24 -20.32 0)
				(effects
					(font
						(size 1.27 1.27)
						(thickness 0.15)
					)
					(justify left bottom)
					(hide yes)
				)
			)
			(property "ki_keywords" "SMT, CAPACITOR, PASSIVE"
				(at 0 0 0)
				(effects
					(font
						(size 1.27 1.27)
					)
					(hide yes)
				)
			)
			(symbol "C_100n_50V_X8L_0402_0_1"
				(polyline
					(pts
						(xy 2.032 -1.524) (xy 2.032 1.524)
					)
					(stroke
						(width 0.3048)
						(type default)
					)
					(fill
						(type none)
					)
				)
				(polyline
					(pts
						(xy 3.048 -1.524) (xy 3.048 1.524)
					)
					(stroke
						(width 0.3302)
						(type default)
					)
					(fill
						(type none)
					)
				)
			)
			(symbol "C_100n_50V_X8L_0402_1_1"
				(pin passive line
					(at 0 0 0)
					(length 2.032)
					(name "~"
						(effects
							(font
								(size 1.27 1.27)
							)
						)
					)
					(number "1"
						(effects
							(font
								(size 1.27 1.27)
							)
						)
					)
				)
				(pin passive line
					(at 5.08 0 180)
					(length 2.032)
					(name "~"
						(effects
							(font
								(size 1.27 1.27)
							)
						)
					)
					(number "2"
						(effects
							(font
								(size 1.27 1.27)
							)
						)
					)
				)
			)
		)
	(symbol "antmicroCapacitors0402:C_1n2_50V_0402"
			(pin_numbers
				(hide yes)
			)
			(pin_names
				(hide yes)
			)
			(exclude_from_sim no)
			(in_bom yes)
			(on_board yes)
			(property "Reference" "C"
				(at 20.32 -5.08 0)
				(effects
					(font
						(size 1.27 1.27)
						(thickness 0.15)
					)
					(justify left bottom)
				)
			)
			(property "Value" "C_1n2_50V_0402"
				(at 20.32 -10.16 0)
				(effects
					(font
						(size 1.27 1.27)
						(thickness 0.15)
					)
					(justify left bottom)
					(hide yes)
				)
			)
			(property "Footprint" "antmicro-footprints:C_0402_1005Metric"
				(at 20.32 -12.7 0)
				(effects
					(font
						(size 1.27 1.27)
						(thickness 0.15)
					)
					(justify left bottom)
					(hide yes)
				)
			)
			(property "Datasheet" "https://www.murata.com/products/productdetail?partno=GCM155R71H122KA37%23"
				(at 20.32 -15.24 0)
				(effects
					(font
						(size 1.27 1.27)
						(thickness 0.15)
					)
					(justify left bottom)
					(hide yes)
				)
			)
			(property "Description" "SMD Multilayer Ceramic Capacitor, 1200 pF, 50 V, 0402 [1005 Metric], ± 10%, X7R, GCM"
				(at 0 0 0)
				(effects
					(font
						(size 1.27 1.27)
					)
					(hide yes)
				)
			)
			(property "MPN" "GCM155R71H122KA37D"
				(at 20.32 -17.78 0)
				(effects
					(font
						(size 1.27 1.27)
						(thickness 0.15)
					)
					(justify left bottom)
					(hide yes)
				)
			)
			(property "Manufacturer" "Murata"
				(at 20.32 -20.32 0)
				(effects
					(font
						(size 1.27 1.27)
						(thickness 0.15)
					)
					(justify left bottom)
					(hide yes)
				)
			)
			(property "License" "Apache-2.0"
				(at 20.32 -22.86 0)
				(effects
					(font
						(size 1.27 1.27)
						(thickness 0.15)
					)
					(justify left bottom)
					(hide yes)
				)
			)
			(property "Author" "Antmicro"
				(at 20.32 -25.4 0)
				(effects
					(font
						(size 1.27 1.27)
						(thickness 0.15)
					)
					(justify left bottom)
					(hide yes)
				)
			)
			(property "Val" "1n2"
				(at 20.32 -7.62 0)
				(effects
					(font
						(size 1.27 1.27)
						(thickness 0.15)
					)
					(justify left bottom)
				)
			)
			(property "Voltage" "50V"
				(at 20.32 -27.94 0)
				(effects
					(font
						(size 1.27 1.27)
					)
					(justify left bottom)
					(hide yes)
				)
			)
			(property "Dielectric" ""
				(at 20.32 -30.48 0)
				(effects
					(font
						(size 1.27 1.27)
					)
					(justify left bottom)
					(hide yes)
				)
			)
			(property "ki_keywords" "0402, SMT, CAPACITOR, PASSIVE, CERAMIC, MLCC"
				(at 0 0 0)
				(effects
					(font
						(size 1.27 1.27)
					)
					(hide yes)
				)
			)
			(symbol "C_1n2_50V_0402_0_1"
				(polyline
					(pts
						(xy 2.032 -1.524) (xy 2.032 1.524)
					)
					(stroke
						(width 0.3048)
						(type default)
					)
					(fill
						(type none)
					)
				)
				(polyline
					(pts
						(xy 3.048 -1.524) (xy 3.048 1.524)
					)
					(stroke
						(width 0.3302)
						(type default)
					)
					(fill
						(type none)
					)
				)
			)
			(symbol "C_1n2_50V_0402_1_1"
				(pin passive line
					(at 0 0 0)
					(length 2.032)
					(name "~"
						(effects
							(font
								(size 1.27 1.27)
							)
						)
					)
					(number "1"
						(effects
							(font
								(size 1.27 1.27)
							)
						)
					)
				)
				(pin passive line
					(at 5.08 0 180)
					(length 2.032)
					(name "~"
						(effects
							(font
								(size 1.27 1.27)
							)
						)
					)
					(number "2"
						(effects
							(font
								(size 1.27 1.27)
							)
						)
					)
				)
			)
		)
	(symbol "antmicroCapacitors0402:C_1u_25V_0402"
			(pin_numbers
				(hide yes)
			)
			(pin_names
				(hide yes)
			)
			(exclude_from_sim no)
			(in_bom yes)
			(on_board yes)
			(property "Reference" "C"
				(at 20.32 -5.08 0)
				(effects
					(font
						(size 1.27 1.27)
						(thickness 0.15)
					)
					(justify left bottom)
				)
			)
			(property "Value" "C_1u_25V_0402"
				(at 20.32 -10.16 0)
				(effects
					(font
						(size 1.27 1.27)
						(thickness 0.15)
					)
					(justify left bottom)
					(hide yes)
				)
			)
			(property "Footprint" "antmicro-footprints:C_0402_1005Metric"
				(at 20.32 -12.7 0)
				(effects
					(font
						(size 1.27 1.27)
						(thickness 0.15)
					)
					(justify left bottom)
					(hide yes)
				)
			)
			(property "Datasheet" "https://www.murata.com/products/productdetail?partno=GRM155R61E105KE11%23"
				(at 20.32 -15.24 0)
				(effects
					(font
						(size 1.27 1.27)
						(thickness 0.15)
					)
					(justify left bottom)
					(hide yes)
				)
			)
			(property "Description" "SMD Multilayer Ceramic Capacitor, 1 µF, 25 V, 0402 [1005 Metric], ± 10%, X5R, GRM Series"
				(at 0 0 0)
				(effects
					(font
						(size 1.27 1.27)
					)
					(hide yes)
				)
			)
			(property "MPN" "GRM155R61E105KE11J"
				(at 20.32 -17.78 0)
				(effects
					(font
						(size 1.27 1.27)
						(thickness 0.15)
					)
					(justify left bottom)
					(hide yes)
				)
			)
			(property "Manufacturer" "Murata"
				(at 20.32 -20.32 0)
				(effects
					(font
						(size 1.27 1.27)
						(thickness 0.15)
					)
					(justify left bottom)
					(hide yes)
				)
			)
			(property "License" "Apache-2.0"
				(at 20.32 -22.86 0)
				(effects
					(font
						(size 1.27 1.27)
						(thickness 0.15)
					)
					(justify left bottom)
					(hide yes)
				)
			)
			(property "Author" "Antmicro"
				(at 20.32 -25.4 0)
				(effects
					(font
						(size 1.27 1.27)
						(thickness 0.15)
					)
					(justify left bottom)
					(hide yes)
				)
			)
			(property "Val" "1u"
				(at 20.32 -7.62 0)
				(effects
					(font
						(size 1.27 1.27)
						(thickness 0.15)
					)
					(justify left bottom)
				)
			)
			(property "Voltage" "25V"
				(at 20.32 -27.94 0)
				(effects
					(font
						(size 1.27 1.27)
					)
					(justify left bottom)
					(hide yes)
				)
			)
			(property "Dielectric" "X5R"
				(at 20.32 -30.48 0)
				(effects
					(font
						(size 1.27 1.27)
					)
					(justify left bottom)
					(hide yes)
				)
			)
			(property "ki_keywords" "0402, SMT, CAPACITOR, PASSIVE, CERAMIC"
				(at 0 0 0)
				(effects
					(font
						(size 1.27 1.27)
					)
					(hide yes)
				)
			)
			(symbol "C_1u_25V_0402_0_1"
				(polyline
					(pts
						(xy 2.032 -1.524) (xy 2.032 1.524)
					)
					(stroke
						(width 0.3048)
						(type default)
					)
					(fill
						(type none)
					)
				)
				(polyline
					(pts
						(xy 3.048 -1.524) (xy 3.048 1.524)
					)
					(stroke
						(width 0.3302)
						(type default)
					)
					(fill
						(type none)
					)
				)
			)
			(symbol "C_1u_25V_0402_1_1"
				(pin passive line
					(at 0 0 0)
					(length 2.032)
					(name "~"
						(effects
							(font
								(size 1.27 1.27)
							)
						)
					)
					(number "1"
						(effects
							(font
								(size 1.27 1.27)
							)
						)
					)
				)
				(pin passive line
					(at 5.08 0 180)
					(length 2.032)
					(name "~"
						(effects
							(font
								(size 1.27 1.27)
							)
						)
					)
					(number "2"
						(effects
							(font
								(size 1.27 1.27)
							)
						)
					)
				)
			)
		)
	(symbol "antmicroCapacitors0402:C_270p_25V_0402"
			(pin_numbers
				(hide yes)
			)
			(pin_names
				(hide yes)
			)
			(exclude_from_sim no)
			(in_bom yes)
			(on_board yes)
			(property "Reference" "C"
				(at 20.32 -5.08 0)
				(effects
					(font
						(size 1.27 1.27)
						(thickness 0.15)
					)
					(justify left bottom)
				)
			)
			(property "Value" "C_270p_25V_0402"
				(at 20.32 -10.16 0)
				(effects
					(font
						(size 1.27 1.27)
						(thickness 0.15)
					)
					(justify left bottom)
					(hide yes)
				)
			)
			(property "Footprint" "antmicro-footprints:C_0402_1005Metric"
				(at 20.32 -12.7 0)
				(effects
					(font
						(size 1.27 1.27)
						(thickness 0.15)
					)
					(justify left bottom)
					(hide yes)
				)
			)
			(property "Datasheet" "https://www.kemet.com/en/us/capacitors/product/C0402C271J3GAC7867.html"
				(at 20.32 -15.24 0)
				(effects
					(font
						(size 1.27 1.27)
						(thickness 0.15)
					)
					(justify left bottom)
					(hide yes)
				)
			)
			(property "Description" "SMD Multilayer Ceramic Capacitor, 270 pF, 25 V, 0402 [1005 Metric], ± 5%, C0G / NP0"
				(at 0 0 0)
				(effects
					(font
						(size 1.27 1.27)
					)
					(hide yes)
				)
			)
			(property "MPN" "C0402C271J3GAC7867"
				(at 20.32 -17.78 0)
				(effects
					(font
						(size 1.27 1.27)
						(thickness 0.15)
					)
					(justify left bottom)
					(hide yes)
				)
			)
			(property "Manufacturer" "KEMET"
				(at 20.32 -20.32 0)
				(effects
					(font
						(size 1.27 1.27)
						(thickness 0.15)
					)
					(justify left bottom)
					(hide yes)
				)
			)
			(property "License" "Apache-2.0"
				(at 20.32 -22.86 0)
				(effects
					(font
						(size 1.27 1.27)
						(thickness 0.15)
					)
					(justify left bottom)
					(hide yes)
				)
			)
			(property "Author" "Antmicro"
				(at 20.32 -25.4 0)
				(effects
					(font
						(size 1.27 1.27)
						(thickness 0.15)
					)
					(justify left bottom)
					(hide yes)
				)
			)
			(property "Val" "270p"
				(at 20.32 -7.62 0)
				(effects
					(font
						(size 1.27 1.27)
						(thickness 0.15)
					)
					(justify left bottom)
				)
			)
			(property "Voltage" "25V"
				(at 20.32 -27.94 0)
				(effects
					(font
						(size 1.27 1.27)
					)
					(justify left bottom)
					(hide yes)
				)
			)
			(property "Dielectric" ""
				(at 20.32 -30.48 0)
				(effects
					(font
						(size 1.27 1.27)
					)
					(justify left bottom)
					(hide yes)
				)
			)
			(property "ki_keywords" "0402, SMT, CAPACITOR, PASSIVE, CERAMIC, MLCC"
				(at 0 0 0)
				(effects
					(font
						(size 1.27 1.27)
					)
					(hide yes)
				)
			)
			(symbol "C_270p_25V_0402_0_1"
				(polyline
					(pts
						(xy 2.032 -1.524) (xy 2.032 1.524)
					)
					(stroke
						(width 0.3048)
						(type default)
					)
					(fill
						(type none)
					)
				)
				(polyline
					(pts
						(xy 3.048 -1.524) (xy 3.048 1.524)
					)
					(stroke
						(width 0.3302)
						(type default)
					)
					(fill
						(type none)
					)
				)
			)
			(symbol "C_270p_25V_0402_1_1"
				(pin passive line
					(at 0 0 0)
					(length 2.032)
					(name "~"
						(effects
							(font
								(size 1.27 1.27)
							)
						)
					)
					(number "1"
						(effects
							(font
								(size 1.27 1.27)
							)
						)
					)
				)
				(pin passive line
					(at 5.08 0 180)
					(length 2.032)
					(name "~"
						(effects
							(font
								(size 1.27 1.27)
							)
						)
					)
					(number "2"
						(effects
							(font
								(size 1.27 1.27)
							)
						)
					)
				)
			)
		)
	(symbol "antmicroCapacitors0402:C_33n_0402"
			(pin_numbers
				(hide yes)
			)
			(pin_names
				(hide yes)
			)
			(exclude_from_sim no)
			(in_bom yes)
			(on_board yes)
			(property "Reference" "C"
				(at 20.32 -5.08 0)
				(effects
					(font
						(size 1.27 1.27)
						(thickness 0.15)
					)
					(justify left bottom)
				)
			)
			(property "Value" "C_33n_0402"
				(at 20.32 -10.16 0)
				(effects
					(font
						(size 1.27 1.27)
						(thickness 0.15)
					)
					(justify left bottom)
					(hide yes)
				)
			)
			(property "Footprint" "antmicro-footprints:C_0402_1005Metric"
				(at 20.32 -12.7 0)
				(effects
					(font
						(size 1.27 1.27)
						(thickness 0.15)
					)
					(justify left bottom)
					(hide yes)
				)
			)
			(property "Datasheet" "https://www.murata.com/products/productdetail?partno=GCM155R71E333KA55%23"
				(at 20.32 -15.24 0)
				(effects
					(font
						(size 1.27 1.27)
						(thickness 0.15)
					)
					(justify left bottom)
					(hide yes)
				)
			)
			(property "Description" "SMD Multilayer Ceramic Capacitor, 33000 pF, 25 V, 0402 [1005 Metric], ± 10%, X7R, MC"
				(at 0 0 0)
				(effects
					(font
						(size 1.27 1.27)
					)
					(hide yes)
				)
			)
			(property "MPN" "GCM155R71E333KA55D"
				(at 20.32 -17.78 0)
				(effects
					(font
						(size 1.27 1.27)
						(thickness 0.15)
					)
					(justify left bottom)
					(hide yes)
				)
			)
			(property "Manufacturer" "Murata"
				(at 20.32 -20.32 0)
				(effects
					(font
						(size 1.27 1.27)
						(thickness 0.15)
					)
					(justify left bottom)
					(hide yes)
				)
			)
			(property "License" "Apache-2.0"
				(at 20.32 -22.86 0)
				(effects
					(font
						(size 1.27 1.27)
						(thickness 0.15)
					)
					(justify left bottom)
					(hide yes)
				)
			)
			(property "Author" "Antmicro"
				(at 20.32 -25.4 0)
				(effects
					(font
						(size 1.27 1.27)
						(thickness 0.15)
					)
					(justify left bottom)
					(hide yes)
				)
			)
			(property "Val" "33n"
				(at 20.32 -7.62 0)
				(effects
					(font
						(size 1.27 1.27)
						(thickness 0.15)
					)
					(justify left bottom)
				)
			)
			(property "Voltage" ""
				(at 20.32 -27.94 0)
				(effects
					(font
						(size 1.27 1.27)
					)
					(justify left bottom)
					(hide yes)
				)
			)
			(property "Dielectric" ""
				(at 20.32 -30.48 0)
				(effects
					(font
						(size 1.27 1.27)
					)
					(justify left bottom)
					(hide yes)
				)
			)
			(property "ki_keywords" "0402, SMT, CAPACITOR, PASSIVE"
				(at 0 0 0)
				(effects
					(font
						(size 1.27 1.27)
					)
					(hide yes)
				)
			)
			(symbol "C_33n_0402_0_1"
				(polyline
					(pts
						(xy 2.032 -1.524) (xy 2.032 1.524)
					)
					(stroke
						(width 0.3048)
						(type default)
					)
					(fill
						(type none)
					)
				)
				(polyline
					(pts
						(xy 3.048 -1.524) (xy 3.048 1.524)
					)
					(stroke
						(width 0.3302)
						(type default)
					)
					(fill
						(type none)
					)
				)
			)
			(symbol "C_33n_0402_1_1"
				(pin passive line
					(at 0 0 0)
					(length 2.032)
					(name "~"
						(effects
							(font
								(size 1.27 1.27)
							)
						)
					)
					(number "1"
						(effects
							(font
								(size 1.27 1.27)
							)
						)
					)
				)
				(pin passive line
					(at 5.08 0 180)
					(length 2.032)
					(name "~"
						(effects
							(font
								(size 1.27 1.27)
							)
						)
					)
					(number "2"
						(effects
							(font
								(size 1.27 1.27)
							)
						)
					)
				)
			)
		)
	(symbol "antmicroCapacitors0402:C_4u7_25V_0402"
			(pin_numbers
				(hide yes)
			)
			(pin_names
				(hide yes)
			)
			(exclude_from_sim no)
			(in_bom yes)
			(on_board yes)
			(property "Reference" "C"
				(at 20.32 -5.08 0)
				(effects
					(font
						(size 1.27 1.27)
						(thickness 0.15)
					)
					(justify left bottom)
				)
			)
			(property "Value" "C_4u7_25V_0402"
				(at 20.32 -10.16 0)
				(effects
					(font
						(size 1.27 1.27)
						(thickness 0.15)
					)
					(justify left bottom)
					(hide yes)
				)
			)
			(property "Footprint" "antmicro-footprints:C_0402_1005Metric"
				(at 20.32 -12.7 0)
				(effects
					(font
						(size 1.27 1.27)
						(thickness 0.15)
					)
					(justify left bottom)
					(hide yes)
				)
			)
			(property "Datasheet" "https://www.murata.com/products/productdetail?partno=GRM155C61E475ME15%23"
				(at 20.32 -15.24 0)
				(effects
					(font
						(size 1.27 1.27)
						(thickness 0.15)
					)
					(justify left bottom)
					(hide yes)
				)
			)
			(property "Description" "SMD Multilayer Ceramic Capacitor"
				(at 0 0 0)
				(effects
					(font
						(size 1.27 1.27)
					)
					(hide yes)
				)
			)
			(property "MPN" "GRM155C61E475ME15J"
				(at 20.32 -17.78 0)
				(effects
					(font
						(size 1.27 1.27)
						(thickness 0.15)
					)
					(justify left bottom)
					(hide yes)
				)
			)
			(property "Manufacturer" "Murata"
				(at 20.32 -20.32 0)
				(effects
					(font
						(size 1.27 1.27)
						(thickness 0.15)
					)
					(justify left bottom)
					(hide yes)
				)
			)
			(property "License" "Apache-2.0"
				(at 20.32 -22.86 0)
				(effects
					(font
						(size 1.27 1.27)
						(thickness 0.15)
					)
					(justify left bottom)
					(hide yes)
				)
			)
			(property "Author" "Antmicro"
				(at 20.32 -25.4 0)
				(effects
					(font
						(size 1.27 1.27)
						(thickness 0.15)
					)
					(justify left bottom)
					(hide yes)
				)
			)
			(property "Val" "4u7"
				(at 20.32 -7.62 0)
				(effects
					(font
						(size 1.27 1.27)
						(thickness 0.15)
					)
					(justify left bottom)
				)
			)
			(property "Voltage" "25V"
				(at 20.32 -27.94 0)
				(effects
					(font
						(size 1.27 1.27)
					)
					(justify left bottom)
					(hide yes)
				)
			)
			(property "Dielectric" "X5S"
				(at 20.32 -30.48 0)
				(effects
					(font
						(size 1.27 1.27)
					)
					(justify left bottom)
					(hide yes)
				)
			)
			(property "ki_keywords" "0402, SMT, CAPACITOR, PASSIVE, CERAMIC"
				(at 0 0 0)
				(effects
					(font
						(size 1.27 1.27)
					)
					(hide yes)
				)
			)
			(symbol "C_4u7_25V_0402_0_1"
				(polyline
					(pts
						(xy 2.032 -1.524) (xy 2.032 1.524)
					)
					(stroke
						(width 0.3048)
						(type default)
					)
					(fill
						(type none)
					)
				)
				(polyline
					(pts
						(xy 3.048 -1.524) (xy 3.048 1.524)
					)
					(stroke
						(width 0.3302)
						(type default)
					)
					(fill
						(type none)
					)
				)
			)
			(symbol "C_4u7_25V_0402_1_1"
				(pin passive line
					(at 0 0 0)
					(length 2.032)
					(name "~"
						(effects
							(font
								(size 1.27 1.27)
							)
						)
					)
					(number "1"
						(effects
							(font
								(size 1.27 1.27)
							)
						)
					)
				)
				(pin passive line
					(at 5.08 0 180)
					(length 2.032)
					(name "~"
						(effects
							(font
								(size 1.27 1.27)
							)
						)
					)
					(number "2"
						(effects
							(font
								(size 1.27 1.27)
							)
						)
					)
				)
			)
		)
	(symbol "antmicroCapacitors0603:C_10u_25V_0603"
			(pin_numbers
				(hide yes)
			)
			(pin_names
				(hide yes)
			)
			(exclude_from_sim no)
			(in_bom yes)
			(on_board yes)
			(property "Reference" "C"
				(at 20.32 -5.08 0)
				(effects
					(font
						(size 1.27 1.27)
						(thickness 0.15)
					)
					(justify left bottom)
				)
			)
			(property "Value" "C_10u_25V_0603"
				(at 20.32 -10.16 0)
				(effects
					(font
						(size 1.27 1.27)
						(thickness 0.15)
					)
					(justify left bottom)
					(hide yes)
				)
			)
			(property "Footprint" "antmicro-footprints:C_0603_1608Metric"
				(at 20.32 -12.7 0)
				(effects
					(font
						(size 1.27 1.27)
						(thickness 0.15)
					)
					(justify left bottom)
					(hide yes)
				)
			)
			(property "Datasheet" "https://product.tdk.com/en/search/capacitor/ceramic/mlcc/info?part_no=C1608X5R1E106M080AC"
				(at 20.32 -15.24 0)
				(effects
					(font
						(size 1.27 1.27)
						(thickness 0.15)
					)
					(justify left bottom)
					(hide yes)
				)
			)
			(property "Description" "SMD Multilayer Ceramic Capacitor, 10 µF, 25 V, 0603 [1608 Metric], ± 20%, X5R, C"
				(at 0 0 0)
				(effects
					(font
						(size 1.27 1.27)
					)
					(hide yes)
				)
			)
			(property "MPN" "C1608X5R1E106M080AC"
				(at 20.32 -17.78 0)
				(effects
					(font
						(size 1.27 1.27)
						(thickness 0.15)
					)
					(justify left bottom)
					(hide yes)
				)
			)
			(property "Manufacturer" "TDK"
				(at 20.32 -20.32 0)
				(effects
					(font
						(size 1.27 1.27)
						(thickness 0.15)
					)
					(justify left bottom)
					(hide yes)
				)
			)
			(property "License" "Apache-2.0"
				(at 20.32 -22.86 0)
				(effects
					(font
						(size 1.27 1.27)
						(thickness 0.15)
					)
					(justify left bottom)
					(hide yes)
				)
			)
			(property "Author" "Antmicro"
				(at 20.32 -25.4 0)
				(effects
					(font
						(size 1.27 1.27)
						(thickness 0.15)
					)
					(justify left bottom)
					(hide yes)
				)
			)
			(property "Val" "10u"
				(at 20.32 -7.62 0)
				(effects
					(font
						(size 1.27 1.27)
						(thickness 0.15)
					)
					(justify left bottom)
				)
			)
			(property "Voltage" "25V"
				(at 20.32 -27.94 0)
				(effects
					(font
						(size 1.27 1.27)
					)
					(justify left bottom)
					(hide yes)
				)
			)
			(property "Dielectric" ""
				(at 20.32 -30.48 0)
				(effects
					(font
						(size 1.27 1.27)
					)
					(justify left bottom)
					(hide yes)
				)
			)
			(property "ki_keywords" "0603, SMT, CAPACITOR, PASSIVE, CERAMIC, MLCC"
				(at 0 0 0)
				(effects
					(font
						(size 1.27 1.27)
					)
					(hide yes)
				)
			)
			(symbol "C_10u_25V_0603_0_1"
				(polyline
					(pts
						(xy 2.032 -1.524) (xy 2.032 1.524)
					)
					(stroke
						(width 0.3048)
						(type default)
					)
					(fill
						(type none)
					)
				)
				(polyline
					(pts
						(xy 3.048 -1.524) (xy 3.048 1.524)
					)
					(stroke
						(width 0.3302)
						(type default)
					)
					(fill
						(type none)
					)
				)
			)
			(symbol "C_10u_25V_0603_1_1"
				(pin passive line
					(at 0 0 0)
					(length 2.032)
					(name "~"
						(effects
							(font
								(size 1.27 1.27)
							)
						)
					)
					(number "1"
						(effects
							(font
								(size 1.27 1.27)
							)
						)
					)
				)
				(pin passive line
					(at 5.08 0 180)
					(length 2.032)
					(name "~"
						(effects
							(font
								(size 1.27 1.27)
							)
						)
					)
					(number "2"
						(effects
							(font
								(size 1.27 1.27)
							)
						)
					)
				)
			)
		)
	(symbol "antmicroCapacitorsmisc:C_10u_0805_35V"
			(pin_numbers
				(hide yes)
			)
			(pin_names
				(hide yes)
			)
			(exclude_from_sim no)
			(in_bom yes)
			(on_board yes)
			(property "Reference" "C"
				(at 20.32 -5.08 0)
				(effects
					(font
						(size 1.27 1.27)
						(thickness 0.15)
					)
					(justify left bottom)
				)
			)
			(property "Value" "C_10u_0805_35V"
				(at 20.32 -10.16 0)
				(effects
					(font
						(size 1.27 1.27)
						(thickness 0.15)
					)
					(justify left bottom)
					(hide yes)
				)
			)
			(property "Footprint" "antmicro-footprints:C_0805_2012Metric"
				(at 20.32 -12.7 0)
				(effects
					(font
						(size 1.27 1.27)
						(thickness 0.15)
					)
					(justify left bottom)
					(hide yes)
				)
			)
			(property "Datasheet" "https://www.murata.com/products/productdetail?partno=GRM21BR6YA106KE43%23"
				(at 20.32 -15.24 0)
				(effects
					(font
						(size 1.27 1.27)
						(thickness 0.15)
					)
					(justify left bottom)
					(hide yes)
				)
			)
			(property "Description" "SMD Multilayer Ceramic Capacitor, 10 µF, 35 V, 0805 [2012 Metric], ± 10%, X5R, GRM Series"
				(at 0 0 0)
				(effects
					(font
						(size 1.27 1.27)
					)
					(hide yes)
				)
			)
			(property "MPN" "GRM21BR6YA106KE43L"
				(at 20.32 -17.78 0)
				(effects
					(font
						(size 1.27 1.27)
						(thickness 0.15)
					)
					(justify left bottom)
					(hide yes)
				)
			)
			(property "Manufacturer" "Murata"
				(at 20.32 -20.32 0)
				(effects
					(font
						(size 1.27 1.27)
						(thickness 0.15)
					)
					(justify left bottom)
					(hide yes)
				)
			)
			(property "License" "Apache-2.0"
				(at 20.32 -22.86 0)
				(effects
					(font
						(size 1.27 1.27)
						(thickness 0.15)
					)
					(justify left bottom)
					(hide yes)
				)
			)
			(property "Author" "Antmicro"
				(at 20.32 -25.4 0)
				(effects
					(font
						(size 1.27 1.27)
						(thickness 0.15)
					)
					(justify left bottom)
					(hide yes)
				)
			)
			(property "Val" "10u"
				(at 20.32 -7.62 0)
				(effects
					(font
						(size 1.27 1.27)
						(thickness 0.15)
					)
					(justify left bottom)
				)
			)
			(property "Voltage" "35V"
				(at 20.32 -27.94 0)
				(effects
					(font
						(size 1.27 1.27)
					)
					(justify left bottom)
					(hide yes)
				)
			)
			(property "Dielectric" ""
				(at 20.32 -30.48 0)
				(effects
					(font
						(size 1.27 1.27)
					)
					(justify left bottom)
					(hide yes)
				)
			)
			(property "Public" "False"
				(at 20.32 -33.02 0)
				(effects
					(font
						(size 1.27 1.27)
					)
					(justify left bottom)
					(hide yes)
				)
			)
			(property "ki_keywords" "0805, SMT, CAPACITOR, PASSIVE"
				(at 0 0 0)
				(effects
					(font
						(size 1.27 1.27)
					)
					(hide yes)
				)
			)
			(symbol "C_10u_0805_35V_0_1"
				(polyline
					(pts
						(xy 2.032 -1.524) (xy 2.032 1.524)
					)
					(stroke
						(width 0.3048)
						(type default)
					)
					(fill
						(type none)
					)
				)
				(polyline
					(pts
						(xy 3.048 -1.524) (xy 3.048 1.524)
					)
					(stroke
						(width 0.3302)
						(type default)
					)
					(fill
						(type none)
					)
				)
			)
			(symbol "C_10u_0805_35V_1_1"
				(pin passive line
					(at 0 0 0)
					(length 2.032)
					(name "~"
						(effects
							(font
								(size 1.27 1.27)
							)
						)
					)
					(number "1"
						(effects
							(font
								(size 1.27 1.27)
							)
						)
					)
				)
				(pin passive line
					(at 5.08 0 180)
					(length 2.032)
					(name "~"
						(effects
							(font
								(size 1.27 1.27)
							)
						)
					)
					(number "2"
						(effects
							(font
								(size 1.27 1.27)
							)
						)
					)
				)
			)
		)
	(symbol "antmicroCapacitorsmisc:C_22u_25V_0805"
			(pin_numbers
				(hide yes)
			)
			(pin_names
				(hide yes)
			)
			(exclude_from_sim no)
			(in_bom yes)
			(on_board yes)
			(property "Reference" "C"
				(at 20.32 -5.08 0)
				(effects
					(font
						(size 1.27 1.27)
						(thickness 0.15)
					)
					(justify left bottom)
				)
			)
			(property "Value" "C_22u_25V_0805"
				(at 20.32 -10.16 0)
				(effects
					(font
						(size 1.27 1.27)
						(thickness 0.15)
					)
					(justify left bottom)
					(hide yes)
				)
			)
			(property "Footprint" "antmicro-footprints:C_0805_2012Metric"
				(at 20.32 -12.7 0)
				(effects
					(font
						(size 1.27 1.27)
						(thickness 0.15)
					)
					(justify left bottom)
					(hide yes)
				)
			)
			(property "Datasheet" "https://product.samsungsem.com/mlcc/CL21A226MAYNNN.do"
				(at 20.32 -15.24 0)
				(effects
					(font
						(size 1.27 1.27)
						(thickness 0.15)
					)
					(justify left bottom)
					(hide yes)
				)
			)
			(property "Description" "SMT Multilayer Ceramic Capacitor, 22uF, +/-20%, 25V, X5R, 0805 [2012 Metric]"
				(at 0 0 0)
				(effects
					(font
						(size 1.27 1.27)
					)
					(hide yes)
				)
			)
			(property "MPN" "CL21A226MAYNNNE"
				(at 20.32 -17.78 0)
				(effects
					(font
						(size 1.27 1.27)
						(thickness 0.15)
					)
					(justify left bottom)
					(hide yes)
				)
			)
			(property "Manufacturer" "Samsung Electro-Mechanics"
				(at 20.32 -20.32 0)
				(effects
					(font
						(size 1.27 1.27)
						(thickness 0.15)
					)
					(justify left bottom)
					(hide yes)
				)
			)
			(property "License" "Apache-2.0"
				(at 20.32 -22.86 0)
				(effects
					(font
						(size 1.27 1.27)
						(thickness 0.15)
					)
					(justify left bottom)
					(hide yes)
				)
			)
			(property "Author" "Antmicro"
				(at 20.32 -25.4 0)
				(effects
					(font
						(size 1.27 1.27)
						(thickness 0.15)
					)
					(justify left bottom)
					(hide yes)
				)
			)
			(property "Val" "22u"
				(at 20.32 -7.62 0)
				(effects
					(font
						(size 1.27 1.27)
						(thickness 0.15)
					)
					(justify left bottom)
				)
			)
			(property "Voltage" "25V"
				(at 20.32 -27.94 0)
				(effects
					(font
						(size 1.27 1.27)
					)
					(justify left bottom)
				)
			)
			(property "Dielectric" "X5R"
				(at 20.32 -30.48 0)
				(effects
					(font
						(size 1.27 1.27)
					)
					(justify left bottom)
					(hide yes)
				)
			)
			(property "Public" "False"
				(at 20.32 -33.02 0)
				(effects
					(font
						(size 1.27 1.27)
					)
					(justify left bottom)
					(hide yes)
				)
			)
			(property "ki_keywords" "0805, SMT, CAPACITOR, PASSIVE"
				(at 0 0 0)
				(effects
					(font
						(size 1.27 1.27)
					)
					(hide yes)
				)
			)
			(symbol "C_22u_25V_0805_0_1"
				(polyline
					(pts
						(xy 2.032 -1.524) (xy 2.032 1.524)
					)
					(stroke
						(width 0.3048)
						(type default)
					)
					(fill
						(type none)
					)
				)
				(polyline
					(pts
						(xy 3.048 -1.524) (xy 3.048 1.524)
					)
					(stroke
						(width 0.3302)
						(type default)
					)
					(fill
						(type none)
					)
				)
			)
			(symbol "C_22u_25V_0805_1_1"
				(pin passive line
					(at 0 0 0)
					(length 2.032)
					(name "~"
						(effects
							(font
								(size 1.27 1.27)
							)
						)
					)
					(number "1"
						(effects
							(font
								(size 1.27 1.27)
							)
						)
					)
				)
				(pin passive line
					(at 5.08 0 180)
					(length 2.032)
					(name "~"
						(effects
							(font
								(size 1.27 1.27)
							)
						)
					)
					(number "2"
						(effects
							(font
								(size 1.27 1.27)
							)
						)
					)
				)
			)
		)
	(symbol "antmicroCapacitorsmisc:C_47u_25V_1206"
			(pin_numbers
				(hide yes)
			)
			(pin_names
				(hide yes)
			)
			(exclude_from_sim no)
			(in_bom yes)
			(on_board yes)
			(property "Reference" "C"
				(at 15.24 -5.08 0)
				(effects
					(font
						(size 1.27 1.27)
						(thickness 0.15)
					)
					(justify left bottom)
				)
			)
			(property "Value" "C_47u_25V_1206"
				(at 15.24 -12.7 0)
				(effects
					(font
						(size 1.27 1.27)
						(thickness 0.15)
					)
					(justify left bottom)
					(hide yes)
				)
			)
			(property "Footprint" "antmicro-footprints:C_1206_3216Metric"
				(at 15.24 -15.24 0)
				(effects
					(font
						(size 1.27 1.27)
						(thickness 0.15)
					)
					(justify left bottom)
					(hide yes)
				)
			)
			(property "Datasheet" "https://product.tdk.com/en/search/capacitor/ceramic/mlcc/info?part_no=C3216X5R1E476M160AC"
				(at 15.24 -17.78 0)
				(effects
					(font
						(size 1.27 1.27)
						(thickness 0.15)
					)
					(justify left bottom)
					(hide yes)
				)
			)
			(property "Description" "SMD Multilayer Ceramic Capacitor, 47 µF, 25 V, 1206 [3216 Metric], ± 20%, X5R"
				(at 0 0 0)
				(effects
					(font
						(size 1.27 1.27)
					)
					(hide yes)
				)
			)
			(property "MPN" "C3216X5R1E476M160AC"
				(at 15.24 -20.32 0)
				(effects
					(font
						(size 1.27 1.27)
						(thickness 0.15)
					)
					(justify left bottom)
					(hide yes)
				)
			)
			(property "Val" "47u"
				(at 15.24 -7.62 0)
				(effects
					(font
						(size 1.27 1.27)
						(thickness 0.15)
					)
					(justify left bottom)
				)
			)
			(property "Dielectric" "X5R"
				(at 15.24 -30.48 0)
				(effects
					(font
						(size 1.27 1.27)
						(thickness 0.15)
					)
					(justify left bottom)
					(hide yes)
				)
			)
			(property "Voltage" "25V"
				(at 15.24 -10.16 0)
				(effects
					(font
						(size 1.27 1.27)
						(thickness 0.15)
					)
					(justify left bottom)
				)
			)
			(property "Manufacturer" "TDK"
				(at 15.24 -27.94 0)
				(effects
					(font
						(size 1.27 1.27)
						(thickness 0.15)
					)
					(justify left bottom)
					(hide yes)
				)
			)
			(property "Author" "Antmicro"
				(at 15.24 -22.86 0)
				(effects
					(font
						(size 1.27 1.27)
						(thickness 0.15)
					)
					(justify left bottom)
					(hide yes)
				)
			)
			(property "License" "Apache-2.0"
				(at 15.24 -25.4 0)
				(effects
					(font
						(size 1.27 1.27)
						(thickness 0.15)
					)
					(justify left bottom)
					(hide yes)
				)
			)
			(property "Public" "False"
				(at 20.32 -33.02 0)
				(effects
					(font
						(size 1.27 1.27)
					)
					(justify left bottom)
					(hide yes)
				)
			)
			(property "ki_keywords" "1206, SMT, CAPACITOR, PASSIVE"
				(at 0 0 0)
				(effects
					(font
						(size 1.27 1.27)
					)
					(hide yes)
				)
			)
			(symbol "C_47u_25V_1206_0_1"
				(polyline
					(pts
						(xy 2.032 -1.524) (xy 2.032 1.524)
					)
					(stroke
						(width 0.3048)
						(type default)
					)
					(fill
						(type none)
					)
				)
				(polyline
					(pts
						(xy 3.048 -1.524) (xy 3.048 1.524)
					)
					(stroke
						(width 0.3302)
						(type default)
					)
					(fill
						(type none)
					)
				)
			)
			(symbol "C_47u_25V_1206_1_1"
				(pin passive line
					(at 0 0 0)
					(length 2.032)
					(name "~"
						(effects
							(font
								(size 1.27 1.27)
							)
						)
					)
					(number "1"
						(effects
							(font
								(size 1.27 1.27)
							)
						)
					)
				)
				(pin passive line
					(at 5.08 0 180)
					(length 2.032)
					(name "~"
						(effects
							(font
								(size 1.27 1.27)
							)
						)
					)
					(number "2"
						(effects
							(font
								(size 1.27 1.27)
							)
						)
					)
				)
			)
		)
	(symbol "antmicroCapacitorspol:C_Pol_150u_30V_Vishay-T59-EE"
			(pin_numbers
				(hide yes)
			)
			(pin_names
				(hide yes)
			)
			(exclude_from_sim no)
			(in_bom yes)
			(on_board yes)
			(property "Reference" "C"
				(at 15.24 -5.08 0)
				(effects
					(font
						(size 1.27 1.27)
						(thickness 0.15)
					)
					(justify left bottom)
				)
			)
			(property "Value" "C_Pol_150u_30V_Vishay-T59-EE"
				(at 15.24 -10.16 0)
				(effects
					(font
						(size 1.27 1.27)
						(thickness 0.15)
					)
					(justify left bottom)
					(hide yes)
				)
			)
			(property "Footprint" "antmicro-footprints:C_Pol_Vishay-T59-EE"
				(at 15.24 -12.7 0)
				(effects
					(font
						(size 1.27 1.27)
						(thickness 0.15)
					)
					(justify left bottom)
					(hide yes)
				)
			)
			(property "Datasheet" "https://www.vishay.com/docs/40191/t59.pdf"
				(at 15.24 -15.24 0)
				(effects
					(font
						(size 1.27 1.27)
						(thickness 0.15)
					)
					(justify left bottom)
					(hide yes)
				)
			)
			(property "Description" "Tantalum Capacitors - Polymer 150uF 30volts 20% 75mohms maxESR"
				(at 0 0 0)
				(effects
					(font
						(size 1.27 1.27)
					)
					(hide yes)
				)
			)
			(property "Manufacturer" "Vishay"
				(at 15.24 -17.78 0)
				(effects
					(font
						(size 1.27 1.27)
						(thickness 0.15)
					)
					(justify left bottom)
					(hide yes)
				)
			)
			(property "MPN" "T59EE157M030C0075"
				(at 15.24 -27.94 0)
				(effects
					(font
						(size 1.27 1.27)
					)
					(justify left bottom)
					(hide yes)
				)
			)
			(property "Voltage" "30V"
				(at 15.24 -20.32 0)
				(effects
					(font
						(size 1.27 1.27)
						(thickness 0.15)
					)
					(justify left bottom)
					(hide yes)
				)
			)
			(property "Val" "150u"
				(at 15.24 -7.62 0)
				(effects
					(font
						(size 1.27 1.27)
						(thickness 0.15)
					)
					(justify left bottom)
				)
			)
			(property "Author" "Antmicro"
				(at 15.24 -22.86 0)
				(effects
					(font
						(size 1.27 1.27)
						(thickness 0.15)
					)
					(justify left bottom)
					(hide yes)
				)
			)
			(property "License" "Apache-2.0"
				(at 15.24 -25.4 0)
				(effects
					(font
						(size 1.27 1.27)
						(thickness 0.15)
					)
					(justify left bottom)
					(hide yes)
				)
			)
			(property "Dielectric" "template_dielectric"
				(at 13.97 -25.4 0)
				(effects
					(font
						(size 1.27 1.27)
					)
					(justify left bottom)
					(hide yes)
				)
			)
			(property "ki_keywords" "SMT, CAPACITOR, PASSIVE, POLARIZED, TANTALUM"
				(at 0 0 0)
				(effects
					(font
						(size 1.27 1.27)
					)
					(hide yes)
				)
			)
			(symbol "C_Pol_150u_30V_Vishay-T59-EE_0_1"
				(polyline
					(pts
						(xy 0.9652 1.27) (xy 0.9652 1.778)
					)
					(stroke
						(width 0)
						(type default)
					)
					(fill
						(type none)
					)
				)
				(polyline
					(pts
						(xy 1.2192 1.524) (xy 0.7112 1.524)
					)
					(stroke
						(width 0)
						(type default)
					)
					(fill
						(type none)
					)
				)
				(rectangle
					(start 1.905 -1.524)
					(end 2.286 1.524)
					(stroke
						(width 0)
						(type default)
					)
					(fill
						(type none)
					)
				)
				(rectangle
					(start 2.921 -1.524)
					(end 3.302 1.524)
					(stroke
						(width 0)
						(type default)
					)
					(fill
						(type outline)
					)
				)
			)
			(symbol "C_Pol_150u_30V_Vishay-T59-EE_1_1"
				(pin passive line
					(at 0 0 0)
					(length 1.8542)
					(name "~"
						(effects
							(font
								(size 1.27 1.27)
							)
						)
					)
					(number "1"
						(effects
							(font
								(size 1.27 1.27)
							)
						)
					)
				)
				(pin passive line
					(at 5.08 0 180)
					(length 1.8542)
					(name "~"
						(effects
							(font
								(size 1.27 1.27)
							)
						)
					)
					(number "2"
						(effects
							(font
								(size 1.27 1.27)
							)
						)
					)
				)
			)
		)
	(symbol "antmicroDCDCConverters:AP62301Z6-7"
			(exclude_from_sim no)
			(in_bom yes)
			(on_board yes)
			(property "Reference" "U"
				(at 30.48 -5.08 0)
				(effects
					(font
						(size 1.27 1.27)
						(thickness 0.15)
					)
					(justify left bottom)
				)
			)
			(property "Value" "AP62301Z6-7"
				(at 30.48 -10.16 0)
				(effects
					(font
						(size 1.27 1.27)
						(thickness 0.15)
					)
					(justify left bottom)
					(hide yes)
				)
			)
			(property "Footprint" "antmicro-footprints:SOT-563"
				(at 30.48 -12.7 0)
				(effects
					(font
						(size 1.27 1.27)
						(thickness 0.15)
					)
					(justify left bottom)
					(hide yes)
				)
			)
			(property "Datasheet" "https://www.diodes.com/assets/Datasheets/AP62300_AP62301_AP62300T.pdf"
				(at 30.48 -15.24 0)
				(effects
					(font
						(size 1.27 1.27)
						(thickness 0.15)
					)
					(justify left bottom)
					(hide yes)
				)
			)
			(property "Description" "DC-DC Switching Synchronous Buck Regulator, Adjustable, 4.2V-18Vin, 0.8V-7V/3A out, SOT-563-6"
				(at 0 0 0)
				(effects
					(font
						(size 1.27 1.27)
					)
					(hide yes)
				)
			)
			(property "MPN" "AP62301Z6-7"
				(at 30.48 -7.62 0)
				(effects
					(font
						(size 1.27 1.27)
						(thickness 0.15)
					)
					(justify left bottom)
				)
			)
			(property "Manufacturer" "Diodes Incorporated"
				(at 30.48 -17.78 0)
				(effects
					(font
						(size 1.27 1.27)
						(thickness 0.15)
					)
					(justify left bottom)
					(hide yes)
				)
			)
			(property "Author" "Antmicro"
				(at 30.48 -20.32 0)
				(effects
					(font
						(size 1.27 1.27)
						(thickness 0.15)
					)
					(justify left bottom)
					(hide yes)
				)
			)
			(property "License" "Apache-2.0"
				(at 30.48 -22.86 0)
				(effects
					(font
						(size 1.27 1.27)
						(thickness 0.15)
					)
					(justify left bottom)
					(hide yes)
				)
			)
			(property "ki_keywords" "SMT, PMIC, IC, VOLTAGE"
				(at 0 0 0)
				(effects
					(font
						(size 1.27 1.27)
					)
					(hide yes)
				)
			)
			(symbol "AP62301Z6-7_1_1"
				(rectangle
					(start 2.54 2.54)
					(end 12.7 -10.16)
					(stroke
						(width 0.254)
						(type default)
					)
					(fill
						(type background)
					)
				)
				(pin power_in line
					(at 0 0 0)
					(length 2.54)
					(name "V_{IN}"
						(effects
							(font
								(size 1.27 1.27)
							)
						)
					)
					(number "1"
						(effects
							(font
								(size 1.27 1.27)
							)
						)
					)
				)
				(pin input line
					(at 0 -5.08 0)
					(length 2.54)
					(name "EN"
						(effects
							(font
								(size 1.27 1.27)
							)
						)
					)
					(number "5"
						(effects
							(font
								(size 1.27 1.27)
							)
						)
					)
				)
				(pin power_in line
					(at 0 -7.62 0)
					(length 2.54)
					(name "GND"
						(effects
							(font
								(size 1.27 1.27)
							)
						)
					)
					(number "3"
						(effects
							(font
								(size 1.27 1.27)
							)
						)
					)
				)
				(pin power_out line
					(at 15.24 0 180)
					(length 2.54)
					(name "SW"
						(effects
							(font
								(size 1.27 1.27)
							)
						)
					)
					(number "2"
						(effects
							(font
								(size 1.27 1.27)
							)
						)
					)
				)
				(pin output line
					(at 15.24 -5.08 180)
					(length 2.54)
					(name "BST"
						(effects
							(font
								(size 1.27 1.27)
							)
						)
					)
					(number "4"
						(effects
							(font
								(size 1.27 1.27)
							)
						)
					)
				)
				(pin input line
					(at 15.24 -7.62 180)
					(length 2.54)
					(name "FB"
						(effects
							(font
								(size 1.27 1.27)
							)
						)
					)
					(number "6"
						(effects
							(font
								(size 1.27 1.27)
							)
						)
					)
				)
			)
		)
	(symbol "antmicroDCDCConverters:SIC477ED-T1-GE3"
			(exclude_from_sim no)
			(in_bom yes)
			(on_board yes)
			(property "Reference" "U"
				(at 50.8 -5.08 0)
				(effects
					(font
						(size 1.27 1.27)
						(thickness 0.15)
					)
					(justify left bottom)
				)
			)
			(property "Value" "SIC477ED-T1-GE3"
				(at 50.8 -7.62 0)
				(effects
					(font
						(size 1.27 1.27)
						(thickness 0.15)
					)
					(justify left bottom)
					(hide yes)
				)
			)
			(property "Footprint" "antmicro-footprints:SIC47XED-T1-GE3"
				(at 50.8 -10.16 0)
				(effects
					(font
						(size 1.27 1.27)
						(thickness 0.15)
					)
					(justify left bottom)
					(hide yes)
				)
			)
			(property "Datasheet" "https://www.vishay.com/docs/77113/sic47x.pdf"
				(at 50.8 -12.7 0)
				(effects
					(font
						(size 1.27 1.27)
						(thickness 0.15)
					)
					(justify left bottom)
					(hide yes)
				)
			)
			(property "Description" "DC/DC Synchronous Regulator, Adjustable, 4.5V to 55VIn, 0.8V to 50.6V/6AOut, 2MHz, PowerPAK MLP55-27"
				(at 0 0 0)
				(effects
					(font
						(size 1.27 1.27)
					)
					(hide yes)
				)
			)
			(property "Manufacturer" "Vishay"
				(at 50.8 -15.24 0)
				(effects
					(font
						(size 1.27 1.27)
						(thickness 0.15)
					)
					(justify left bottom)
					(hide yes)
				)
			)
			(property "MPN" "SIC477ED-T1-GE3"
				(at 50.8 -17.78 0)
				(effects
					(font
						(size 1.27 1.27)
						(thickness 0.15)
					)
					(justify left bottom)
				)
			)
			(property "Author" "Antmicro"
				(at 50.8 -20.32 0)
				(effects
					(font
						(size 1.27 1.27)
						(thickness 0.15)
					)
					(justify left bottom)
					(hide yes)
				)
			)
			(property "License" "Apache-2.0"
				(at 50.8 -22.86 0)
				(effects
					(font
						(size 1.27 1.27)
						(thickness 0.15)
					)
					(justify left bottom)
					(hide yes)
				)
			)
			(property "ki_keywords" "SMT, PMIC, IC, DC-DC, CONVERTER, SWITCHING, VOLTAGE"
				(at 0 0 0)
				(effects
					(font
						(size 1.27 1.27)
					)
					(hide yes)
				)
			)
			(symbol "SIC477ED-T1-GE3_1_1"
				(rectangle
					(start 2.54 2.54)
					(end 25.4 -27.94)
					(stroke
						(width 0.254)
						(type default)
					)
					(fill
						(type background)
					)
				)
				(pin input line
					(at 0 0 0)
					(length 2.54)
					(name "V_{CIN}"
						(effects
							(font
								(size 1.27 1.27)
							)
						)
					)
					(number "1"
						(effects
							(font
								(size 1.27 1.27)
							)
						)
					)
				)
				(pin input line
					(at 0 -2.54 0)
					(length 2.54)
					(name "V_{IN}"
						(effects
							(font
								(size 1.27 1.27)
							)
						)
					)
					(number "7"
						(effects
							(font
								(size 1.27 1.27)
							)
						)
					)
				)
				(pin passive line
					(at 0 -2.54 0)
					(length 2.54)
					(hide yes)
					(name "V_{IN}"
						(effects
							(font
								(size 1.27 1.27)
							)
						)
					)
					(number "8"
						(effects
							(font
								(size 1.27 1.27)
							)
						)
					)
				)
				(pin input line
					(at 0 -5.08 0)
					(length 2.54)
					(name "EN"
						(effects
							(font
								(size 1.27 1.27)
							)
						)
					)
					(number "3"
						(effects
							(font
								(size 1.27 1.27)
							)
						)
					)
				)
				(pin power_out line
					(at 0 -10.16 0)
					(length 2.54)
					(name "V_{DD}"
						(effects
							(font
								(size 1.27 1.27)
							)
						)
					)
					(number "26"
						(effects
							(font
								(size 1.27 1.27)
							)
						)
					)
				)
				(pin passive line
					(at 0 -12.7 0)
					(length 2.54)
					(name "V_{DRV}"
						(effects
							(font
								(size 1.27 1.27)
							)
						)
					)
					(number "16"
						(effects
							(font
								(size 1.27 1.27)
							)
						)
					)
				)
				(pin bidirectional line
					(at 0 -15.24 0)
					(length 2.54)
					(name "MODE"
						(effects
							(font
								(size 1.27 1.27)
							)
						)
					)
					(number "27"
						(effects
							(font
								(size 1.27 1.27)
							)
						)
					)
				)
				(pin passive line
					(at 0 -17.78 0)
					(length 2.54)
					(name "NC"
						(effects
							(font
								(size 1.27 1.27)
							)
						)
					)
					(number "18"
						(effects
							(font
								(size 1.27 1.27)
							)
						)
					)
				)
				(pin passive line
					(at 0 -20.32 0)
					(length 2.54)
					(name "SS"
						(effects
							(font
								(size 1.27 1.27)
							)
						)
					)
					(number "19"
						(effects
							(font
								(size 1.27 1.27)
							)
						)
					)
				)
				(pin passive line
					(at 0 -22.86 0)
					(length 2.54)
					(name "I_{LIMIT}"
						(effects
							(font
								(size 1.27 1.27)
							)
						)
					)
					(number "25"
						(effects
							(font
								(size 1.27 1.27)
							)
						)
					)
				)
				(pin passive line
					(at 0 -25.4 0)
					(length 2.54)
					(name "f_{SW}"
						(effects
							(font
								(size 1.27 1.27)
							)
						)
					)
					(number "24"
						(effects
							(font
								(size 1.27 1.27)
							)
						)
					)
				)
				(pin input line
					(at 27.94 0 180)
					(length 2.54)
					(name "BOOT"
						(effects
							(font
								(size 1.27 1.27)
							)
						)
					)
					(number "4"
						(effects
							(font
								(size 1.27 1.27)
							)
						)
					)
				)
				(pin bidirectional line
					(at 27.94 -2.54 180)
					(length 2.54)
					(name "PHASE"
						(effects
							(font
								(size 1.27 1.27)
							)
						)
					)
					(number "5"
						(effects
							(font
								(size 1.27 1.27)
							)
						)
					)
				)
				(pin passive line
					(at 27.94 -2.54 180)
					(length 2.54)
					(hide yes)
					(name "PHASE"
						(effects
							(font
								(size 1.27 1.27)
							)
						)
					)
					(number "6"
						(effects
							(font
								(size 1.27 1.27)
							)
						)
					)
				)
				(pin bidirectional line
					(at 27.94 -5.08 180)
					(length 2.54)
					(name "SW"
						(effects
							(font
								(size 1.27 1.27)
							)
						)
					)
					(number "12"
						(effects
							(font
								(size 1.27 1.27)
							)
						)
					)
				)
				(pin passive line
					(at 27.94 -5.08 180)
					(length 2.54)
					(hide yes)
					(name "SW"
						(effects
							(font
								(size 1.27 1.27)
							)
						)
					)
					(number "13"
						(effects
							(font
								(size 1.27 1.27)
							)
						)
					)
				)
				(pin passive line
					(at 27.94 -5.08 180)
					(length 2.54)
					(hide yes)
					(name "SW"
						(effects
							(font
								(size 1.27 1.27)
							)
						)
					)
					(number "14"
						(effects
							(font
								(size 1.27 1.27)
							)
						)
					)
				)
				(pin input line
					(at 27.94 -7.62 180)
					(length 2.54)
					(name "GL"
						(effects
							(font
								(size 1.27 1.27)
							)
						)
					)
					(number "15"
						(effects
							(font
								(size 1.27 1.27)
							)
						)
					)
				)
				(pin power_in line
					(at 27.94 -10.16 180)
					(length 2.54)
					(name "V_{SNS}"
						(effects
							(font
								(size 1.27 1.27)
							)
						)
					)
					(number "20"
						(effects
							(font
								(size 1.27 1.27)
							)
						)
					)
				)
				(pin input line
					(at 27.94 -12.7 180)
					(length 2.54)
					(name "V_{FB}"
						(effects
							(font
								(size 1.27 1.27)
							)
						)
					)
					(number "22"
						(effects
							(font
								(size 1.27 1.27)
							)
						)
					)
				)
				(pin passive line
					(at 27.94 -15.24 180)
					(length 2.54)
					(name "NC"
						(effects
							(font
								(size 1.27 1.27)
							)
						)
					)
					(number "21"
						(effects
							(font
								(size 1.27 1.27)
							)
						)
					)
				)
				(pin output line
					(at 27.94 -20.32 180)
					(length 2.54)
					(name "P_{GOOD}"
						(effects
							(font
								(size 1.27 1.27)
							)
						)
					)
					(number "2"
						(effects
							(font
								(size 1.27 1.27)
							)
						)
					)
				)
				(pin passive line
					(at 27.94 -22.86 180)
					(length 2.54)
					(hide yes)
					(name "PGND"
						(effects
							(font
								(size 1.27 1.27)
							)
						)
					)
					(number "10"
						(effects
							(font
								(size 1.27 1.27)
							)
						)
					)
				)
				(pin passive line
					(at 27.94 -22.86 180)
					(length 2.54)
					(hide yes)
					(name "PGND"
						(effects
							(font
								(size 1.27 1.27)
							)
						)
					)
					(number "11"
						(effects
							(font
								(size 1.27 1.27)
							)
						)
					)
				)
				(pin passive line
					(at 27.94 -22.86 180)
					(length 2.54)
					(hide yes)
					(name "PGND"
						(effects
							(font
								(size 1.27 1.27)
							)
						)
					)
					(number "17"
						(effects
							(font
								(size 1.27 1.27)
							)
						)
					)
				)
				(pin power_in line
					(at 27.94 -22.86 180)
					(length 2.54)
					(name "PGND"
						(effects
							(font
								(size 1.27 1.27)
							)
						)
					)
					(number "9"
						(effects
							(font
								(size 1.27 1.27)
							)
						)
					)
				)
				(pin power_in line
					(at 27.94 -25.4 180)
					(length 2.54)
					(name "AGND"
						(effects
							(font
								(size 1.27 1.27)
							)
						)
					)
					(number "23"
						(effects
							(font
								(size 1.27 1.27)
							)
						)
					)
				)
				(pin passive line
					(at 27.94 -25.4 180)
					(length 2.54)
					(hide yes)
					(name "AGND"
						(effects
							(font
								(size 1.27 1.27)
							)
						)
					)
					(number "28"
						(effects
							(font
								(size 1.27 1.27)
							)
						)
					)
				)
			)
		)
	(symbol "antmicroDiodesRectifiersSingle:PMEG6002EJ,115"
			(pin_numbers
				(hide yes)
			)
			(pin_names
				(hide yes)
			)
			(exclude_from_sim no)
			(in_bom yes)
			(on_board yes)
			(property "Reference" "D"
				(at 21.59 -5.08 0)
				(effects
					(font
						(size 1.27 1.27)
						(thickness 0.15)
					)
					(justify left bottom)
				)
			)
			(property "Value" "PMEG6002EJ,115"
				(at 21.59 -15.24 0)
				(effects
					(font
						(size 1.27 1.27)
						(thickness 0.15)
					)
					(justify left bottom)
					(hide yes)
				)
			)
			(property "Footprint" "antmicro-footprints:D_SOD-323F"
				(at 21.59 -10.16 0)
				(effects
					(font
						(size 1.27 1.27)
						(thickness 0.15)
					)
					(justify left bottom)
					(hide yes)
				)
			)
			(property "Datasheet" "https://assets.nexperia.com/documents/data-sheet/PMEG6002EJ.pdf"
				(at 21.59 -12.7 0)
				(effects
					(font
						(size 1.27 1.27)
						(thickness 0.15)
					)
					(justify left bottom)
					(hide yes)
				)
			)
			(property "Description" "Schottky Rectifier, Low VF, 60 V, 200 mA, Single, SOD-323F, 2 Pins, 600 mV"
				(at 0 0 0)
				(effects
					(font
						(size 1.27 1.27)
					)
					(hide yes)
				)
			)
			(property "MPN" "PMEG6002EJ,115"
				(at 21.59 -7.62 0)
				(effects
					(font
						(size 1.27 1.27)
						(thickness 0.15)
					)
					(justify left bottom)
				)
			)
			(property "Manufacturer" "Nexperia"
				(at 21.59 -17.78 0)
				(effects
					(font
						(size 1.27 1.27)
						(thickness 0.15)
					)
					(justify left bottom)
					(hide yes)
				)
			)
			(property "Author" "Antmicro"
				(at 21.59 -20.32 0)
				(effects
					(font
						(size 1.27 1.27)
						(thickness 0.15)
					)
					(justify left bottom)
					(hide yes)
				)
			)
			(property "License" "Apache-2.0"
				(at 21.59 -22.86 0)
				(effects
					(font
						(size 1.27 1.27)
						(thickness 0.15)
					)
					(justify left bottom)
					(hide yes)
				)
			)
			(property "ki_keywords" "SMT, DIODE, SEMICONDUCTOR, RECTIFIER, SCHOTTKY"
				(at 0 0 0)
				(effects
					(font
						(size 1.27 1.27)
					)
					(hide yes)
				)
			)
			(symbol "PMEG6002EJ,115_0_1"
				(polyline
					(pts
						(xy 1.905 0) (xy 0.635 0)
					)
					(stroke
						(width 0)
						(type default)
					)
					(fill
						(type none)
					)
				)
				(polyline
					(pts
						(xy 4.445 0) (xy 3.175 0)
					)
					(stroke
						(width 0)
						(type default)
					)
					(fill
						(type none)
					)
				)
			)
			(symbol "PMEG6002EJ,115_1_1"
				(polyline
					(pts
						(xy 1.778 1.016) (xy 1.778 -1.016)
					)
					(stroke
						(width 0.254)
						(type default)
					)
					(fill
						(type none)
					)
				)
				(polyline
					(pts
						(xy 1.778 1.016) (xy 1.397 1.016) (xy 1.397 0.762)
					)
					(stroke
						(width 0.254)
						(type default)
					)
					(fill
						(type none)
					)
				)
				(polyline
					(pts
						(xy 1.778 -1.016) (xy 2.159 -1.016) (xy 2.159 -0.762)
					)
					(stroke
						(width 0.254)
						(type default)
					)
					(fill
						(type none)
					)
				)
				(polyline
					(pts
						(xy 3.302 1.016) (xy 3.302 -1.016) (xy 1.778 0) (xy 3.302 1.016)
					)
					(stroke
						(width 0.254)
						(type default)
					)
					(fill
						(type outline)
					)
				)
				(pin passive line
					(at 0 0 0)
					(length 0.635)
					(name "C"
						(effects
							(font
								(size 1.27 1.27)
							)
						)
					)
					(number "1"
						(effects
							(font
								(size 1.27 1.27)
							)
						)
					)
				)
				(pin passive line
					(at 5.08 0 180)
					(length 0.635)
					(name "A"
						(effects
							(font
								(size 1.27 1.27)
							)
						)
					)
					(number "2"
						(effects
							(font
								(size 1.27 1.27)
							)
						)
					)
				)
			)
		)
	(symbol "antmicroFerriteBeadsandChips:FB_10Z_10A_WE-MPSB_1206"
			(pin_numbers
				(hide yes)
			)
			(pin_names
				(hide yes)
			)
			(exclude_from_sim no)
			(in_bom yes)
			(on_board yes)
			(property "Reference" "FB"
				(at 13.97 0 0)
				(effects
					(font
						(size 1.27 1.27)
						(thickness 0.15)
					)
					(justify left bottom)
				)
			)
			(property "Value" "FB_10Z_10A_WE-MPSB_1206"
				(at 13.97 -2.54 0)
				(effects
					(font
						(size 1.27 1.27)
						(thickness 0.15)
					)
					(justify left bottom)
					(hide yes)
				)
			)
			(property "Footprint" "antmicro-footprints:FB_1206_3216Metric"
				(at 13.97 -7.62 0)
				(effects
					(font
						(size 1.27 1.27)
						(thickness 0.15)
					)
					(justify left bottom)
					(hide yes)
				)
			)
			(property "Datasheet" "https://www.we-online.com/catalog/datasheet/74279221100.pdf"
				(at 13.97 -10.16 0)
				(effects
					(font
						(size 1.27 1.27)
						(thickness 0.15)
					)
					(justify left bottom)
					(hide yes)
				)
			)
			(property "Description" "Ferrite Bead, 1206 [3216 Metric], 10 ohm, 10.5 A, WE-MPSB, 0.003 ohm, ± 25%, High Current"
				(at 0 0 0)
				(effects
					(font
						(size 1.27 1.27)
					)
					(hide yes)
				)
			)
			(property "Val" "10Z/10A"
				(at 13.97 -5.08 0)
				(effects
					(font
						(size 1.27 1.27)
					)
					(justify left bottom)
				)
			)
			(property "MPN" "74279221100"
				(at 13.97 -12.7 0)
				(effects
					(font
						(size 1.27 1.27)
						(thickness 0.15)
					)
					(justify left bottom)
					(hide yes)
				)
			)
			(property "Manufacturer" "Würth Elektronik"
				(at 13.97 -15.24 0)
				(effects
					(font
						(size 1.27 1.27)
						(thickness 0.15)
					)
					(justify left bottom)
					(hide yes)
				)
			)
			(property "Current" ""
				(at 20.32 -22.86 0)
				(effects
					(font
						(size 1.27 1.27)
						(thickness 0.15)
					)
					(justify left bottom)
					(hide yes)
				)
			)
			(property "Author" "Antmicro"
				(at 13.97 -17.78 0)
				(effects
					(font
						(size 1.27 1.27)
						(thickness 0.15)
					)
					(justify left bottom)
					(hide yes)
				)
			)
			(property "License" "Apache-2.0"
				(at 13.97 -20.32 0)
				(effects
					(font
						(size 1.27 1.27)
						(thickness 0.15)
					)
					(justify left bottom)
					(hide yes)
				)
			)
			(property "ki_keywords" "1206, SMT, FERRITE BEAD, PASSIVE"
				(at 0 0 0)
				(effects
					(font
						(size 1.27 1.27)
					)
					(hide yes)
				)
			)
			(symbol "FB_10Z_10A_WE-MPSB_1206_0_1"
				(polyline
					(pts
						(xy 1.651 0) (xy 1.2446 0)
					)
					(stroke
						(width 0)
						(type default)
					)
					(fill
						(type none)
					)
				)
				(polyline
					(pts
						(xy 2.2606 -1.8288) (xy 1.0414 -1.1176) (xy 2.7432 1.8288) (xy 3.9624 1.1176) (xy 2.2606 -1.8288)
					)
					(stroke
						(width 0)
						(type default)
					)
					(fill
						(type none)
					)
				)
				(polyline
					(pts
						(xy 3.81 0) (xy 3.3274 0)
					)
					(stroke
						(width 0)
						(type default)
					)
					(fill
						(type none)
					)
				)
			)
			(symbol "FB_10Z_10A_WE-MPSB_1206_1_1"
				(pin passive line
					(at 0 0 0)
					(length 1.27)
					(name "~"
						(effects
							(font
								(size 1.27 1.27)
							)
						)
					)
					(number "1"
						(effects
							(font
								(size 1.27 1.27)
							)
						)
					)
				)
				(pin passive line
					(at 5.08 0 180)
					(length 1.27)
					(name "~"
						(effects
							(font
								(size 1.27 1.27)
							)
						)
					)
					(number "2"
						(effects
							(font
								(size 1.27 1.27)
							)
						)
					)
				)
			)
		)
	(symbol "antmicroFixedInductors:L_3u3_2.5A_1008"
			(pin_numbers
				(hide yes)
			)
			(pin_names
				(hide yes)
			)
			(exclude_from_sim no)
			(in_bom yes)
			(on_board yes)
			(property "Reference" "L"
				(at 15.24 0 0)
				(effects
					(font
						(size 1.27 1.27)
						(thickness 0.15)
					)
					(justify left bottom)
				)
			)
			(property "Value" "L_3u3_2.5A_1008"
				(at 15.24 -2.54 0)
				(effects
					(font
						(size 1.27 1.27)
						(thickness 0.15)
					)
					(justify left bottom)
					(hide yes)
				)
			)
			(property "Footprint" "antmicro-footprints:L_1008_2520Metric"
				(at 15.24 -7.62 0)
				(effects
					(font
						(size 1.27 1.27)
						(thickness 0.15)
					)
					(justify left bottom)
					(hide yes)
				)
			)
			(property "Datasheet" "https://product.tdk.com/system/files/dam/doc/product/inductor/inductor/smd/catalog/inductor_automotive_power_tfm252012alma_en.pdf"
				(at 15.24 -10.16 0)
				(effects
					(font
						(size 1.27 1.27)
						(thickness 0.15)
					)
					(justify left bottom)
					(hide yes)
				)
			)
			(property "Description" "3.3 µH Shielded Thin Film Inductor 2 A 140mOhm Max 1008 (2520 Metric)"
				(at 0 0 0)
				(effects
					(font
						(size 1.27 1.27)
					)
					(hide yes)
				)
			)
			(property "MPN" "TFM252012ALMA3R3MTAA"
				(at 15.24 -12.7 0)
				(effects
					(font
						(size 1.27 1.27)
						(thickness 0.15)
					)
					(justify left bottom)
					(hide yes)
				)
			)
			(property "ISat" "2.1 A"
				(at 15.24 -15.24 0)
				(effects
					(font
						(size 1.27 1.27)
						(thickness 0.15)
					)
					(justify left bottom)
					(hide yes)
				)
			)
			(property "IMax" "2.5 A"
				(at 15.24 -17.78 0)
				(effects
					(font
						(size 1.27 1.27)
						(thickness 0.15)
					)
					(justify left bottom)
					(hide yes)
				)
			)
			(property "Manufacturer" "TDK"
				(at 15.24 -20.32 0)
				(effects
					(font
						(size 1.27 1.27)
						(thickness 0.15)
					)
					(justify left bottom)
					(hide yes)
				)
			)
			(property "Val" "3u3/2.5A"
				(at 15.24 -5.08 0)
				(effects
					(font
						(size 1.27 1.27)
						(thickness 0.15)
					)
					(justify left bottom)
				)
			)
			(property "Size" "2.5x2.0"
				(at 15.24 -22.86 0)
				(effects
					(font
						(size 1.27 1.27)
					)
					(justify left bottom)
					(hide yes)
				)
			)
			(property "Author" "Antmicro"
				(at 15.24 -25.4 0)
				(effects
					(font
						(size 1.27 1.27)
						(thickness 0.15)
					)
					(justify left bottom)
					(hide yes)
				)
			)
			(property "License" "Apache-2.0"
				(at 15.24 -27.94 0)
				(effects
					(font
						(size 1.27 1.27)
						(thickness 0.15)
					)
					(justify left bottom)
					(hide yes)
				)
			)
			(property "ki_keywords" "SMT, INDUCTOR, PASSIVE"
				(at 0 0 0)
				(effects
					(font
						(size 1.27 1.27)
					)
					(hide yes)
				)
			)
			(symbol "L_3u3_2.5A_1008_0_1"
				(arc
					(start 0.508 0)
					(mid 1.016 0.5058)
					(end 1.524 0)
					(stroke
						(width 0)
						(type default)
					)
					(fill
						(type none)
					)
				)
				(arc
					(start 1.524 0)
					(mid 2.032 0.5058)
					(end 2.54 0)
					(stroke
						(width 0)
						(type default)
					)
					(fill
						(type none)
					)
				)
				(arc
					(start 2.54 0)
					(mid 3.048 0.5058)
					(end 3.556 0)
					(stroke
						(width 0)
						(type default)
					)
					(fill
						(type none)
					)
				)
				(arc
					(start 3.556 0)
					(mid 4.064 0.5058)
					(end 4.572 0)
					(stroke
						(width 0)
						(type default)
					)
					(fill
						(type none)
					)
				)
			)
			(symbol "L_3u3_2.5A_1008_1_1"
				(pin passive line
					(at 0 0 0)
					(length 0.508)
					(name "~"
						(effects
							(font
								(size 1.27 1.27)
							)
						)
					)
					(number "1"
						(effects
							(font
								(size 1.27 1.27)
							)
						)
					)
				)
				(pin passive line
					(at 5.08 0 180)
					(length 0.508)
					(name "~"
						(effects
							(font
								(size 1.27 1.27)
							)
						)
					)
					(number "2"
						(effects
							(font
								(size 1.27 1.27)
							)
						)
					)
				)
			)
		)
	(symbol "antmicroFixedInductors:L_4u7_14.6A_Abracon-Q8080"
			(pin_numbers
				(hide yes)
			)
			(pin_names
				(hide yes)
			)
			(exclude_from_sim no)
			(in_bom yes)
			(on_board yes)
			(property "Reference" "L"
				(at 15.24 -5.08 0)
				(effects
					(font
						(size 1.27 1.27)
						(thickness 0.15)
					)
					(justify left bottom)
				)
			)
			(property "Value" "L_4u7_14.6A_Abracon-Q8080"
				(at 15.24 -10.16 0)
				(effects
					(font
						(size 1.27 1.27)
						(thickness 0.15)
					)
					(justify left bottom)
					(hide yes)
				)
			)
			(property "Footprint" "antmicro-footprints:L_Abracon_ASPIAIG-Q8080"
				(at 15.24 -12.7 0)
				(effects
					(font
						(size 1.27 1.27)
						(thickness 0.15)
					)
					(justify left bottom)
					(hide yes)
				)
			)
			(property "Datasheet" "https://www.mouser.com/datasheet/2/3/ASPIAIG_Q8080-2256550.pdf"
				(at 15.24 -15.24 0)
				(effects
					(font
						(size 1.27 1.27)
						(thickness 0.15)
					)
					(justify left bottom)
					(hide yes)
				)
			)
			(property "Description" "Power Inductors - SMD 4.7 UH 20%"
				(at 0 0 0)
				(effects
					(font
						(size 1.27 1.27)
					)
					(hide yes)
				)
			)
			(property "MPN" "ASPIAIG-Q8080-4R7M-T"
				(at 15.24 -17.78 0)
				(effects
					(font
						(size 1.27 1.27)
						(thickness 0.15)
					)
					(justify left bottom)
					(hide yes)
				)
			)
			(property "ISat" "17A"
				(at 15.24 -20.32 0)
				(effects
					(font
						(size 1.27 1.27)
						(thickness 0.15)
					)
					(justify left bottom)
					(hide yes)
				)
			)
			(property "IMax" "14.6A"
				(at 15.24 -22.86 0)
				(effects
					(font
						(size 1.27 1.27)
						(thickness 0.15)
					)
					(justify left bottom)
					(hide yes)
				)
			)
			(property "Size" "8.9x8.5"
				(at 15.24 -25.4 0)
				(effects
					(font
						(size 1.27 1.27)
						(thickness 0.15)
					)
					(justify left bottom)
					(hide yes)
				)
			)
			(property "Val" "4.7u/14.6A"
				(at 15.24 -7.62 0)
				(effects
					(font
						(size 1.27 1.27)
						(thickness 0.15)
					)
					(justify left bottom)
				)
			)
			(property "Author" "Antmicro"
				(at 15.24 -27.94 0)
				(effects
					(font
						(size 1.27 1.27)
						(thickness 0.15)
					)
					(justify left bottom)
					(hide yes)
				)
			)
			(property "License" "Apache-2.0"
				(at 15.24 -30.48 0)
				(effects
					(font
						(size 1.27 1.27)
						(thickness 0.15)
					)
					(justify left bottom)
					(hide yes)
				)
			)
			(property "Manufacturer" "Abracon"
				(at 15.24 -33.02 0)
				(effects
					(font
						(size 1.27 1.27)
						(thickness 0.15)
					)
					(justify left bottom)
					(hide yes)
				)
			)
			(property "ki_keywords" "SMT, INDUCTOR, PASSIVE"
				(at 0 0 0)
				(effects
					(font
						(size 1.27 1.27)
					)
					(hide yes)
				)
			)
			(symbol "L_4u7_14.6A_Abracon-Q8080_0_1"
				(arc
					(start 0.508 0)
					(mid 1.016 0.5058)
					(end 1.524 0)
					(stroke
						(width 0)
						(type default)
					)
					(fill
						(type none)
					)
				)
				(arc
					(start 1.524 0)
					(mid 2.032 0.5058)
					(end 2.54 0)
					(stroke
						(width 0)
						(type default)
					)
					(fill
						(type none)
					)
				)
				(arc
					(start 2.54 0)
					(mid 3.048 0.5058)
					(end 3.556 0)
					(stroke
						(width 0)
						(type default)
					)
					(fill
						(type none)
					)
				)
				(arc
					(start 3.556 0)
					(mid 4.064 0.5058)
					(end 4.572 0)
					(stroke
						(width 0)
						(type default)
					)
					(fill
						(type none)
					)
				)
			)
			(symbol "L_4u7_14.6A_Abracon-Q8080_1_1"
				(pin passive line
					(at 0 0 0)
					(length 0.508)
					(name "~"
						(effects
							(font
								(size 1.27 1.27)
							)
						)
					)
					(number "1"
						(effects
							(font
								(size 1.27 1.27)
							)
						)
					)
				)
				(pin passive line
					(at 5.08 0 180)
					(length 0.508)
					(name "~"
						(effects
							(font
								(size 1.27 1.27)
							)
						)
					)
					(number "2"
						(effects
							(font
								(size 1.27 1.27)
							)
						)
					)
				)
			)
		)
	(symbol "antmicroFuses:F_7A_1206"
			(pin_numbers
				(hide yes)
			)
			(pin_names
				(hide yes)
			)
			(exclude_from_sim no)
			(in_bom yes)
			(on_board yes)
			(property "Reference" "F"
				(at 21.59 -5.08 0)
				(effects
					(font
						(size 1.27 1.27)
						(thickness 0.15)
					)
					(justify left bottom)
				)
			)
			(property "Value" "F_7A_1206"
				(at 21.59 -7.62 0)
				(effects
					(font
						(size 1.27 1.27)
						(thickness 0.15)
					)
					(justify left bottom)
					(hide yes)
				)
			)
			(property "Footprint" "antmicro-footprints:F_1206_3216Metric"
				(at 21.59 -10.16 0)
				(effects
					(font
						(size 1.27 1.27)
						(thickness 0.15)
					)
					(justify left bottom)
					(hide yes)
				)
			)
			(property "Datasheet" "https://us.schurter.com/pdf/english/typ_UST_1206.pdf"
				(at 21.59 -12.7 0)
				(effects
					(font
						(size 1.27 1.27)
						(thickness 0.15)
					)
					(justify left bottom)
					(hide yes)
				)
			)
			(property "Description" "7 A 32 V AC 63 V DC Fuse Board Mount (Cartridge Style Excluded) Surface Mount 1206 (3216 Metric)"
				(at 0 0 0)
				(effects
					(font
						(size 1.27 1.27)
					)
					(hide yes)
				)
			)
			(property "Manufacturer" "Schurter"
				(at 21.59 -15.24 0)
				(effects
					(font
						(size 1.27 1.27)
						(thickness 0.15)
					)
					(justify left bottom)
					(hide yes)
				)
			)
			(property "MPN" "3413.0326.11"
				(at 21.59 -17.78 0)
				(effects
					(font
						(size 1.27 1.27)
						(thickness 0.15)
					)
					(justify left bottom)
				)
			)
			(property "Author" "Antmicro"
				(at 21.59 -20.32 0)
				(effects
					(font
						(size 1.27 1.27)
						(thickness 0.15)
					)
					(justify left bottom)
					(hide yes)
				)
			)
			(property "License" "Apache-2.0"
				(at 21.59 -22.86 0)
				(effects
					(font
						(size 1.27 1.27)
						(thickness 0.15)
					)
					(justify left bottom)
					(hide yes)
				)
			)
			(property "ki_keywords" "FUSE, PASSIVE"
				(at 0 0 0)
				(effects
					(font
						(size 1.27 1.27)
					)
					(hide yes)
				)
			)
			(symbol "F_7A_1206_0_1"
				(rectangle
					(start 1.27 0.508)
					(end 3.81 -0.508)
					(stroke
						(width 0)
						(type default)
					)
					(fill
						(type none)
					)
				)
				(polyline
					(pts
						(xy 1.27 0) (xy 3.81 0)
					)
					(stroke
						(width 0)
						(type default)
					)
					(fill
						(type none)
					)
				)
			)
			(symbol "F_7A_1206_1_1"
				(pin passive line
					(at 0 0 0)
					(length 1.27)
					(name "~"
						(effects
							(font
								(size 1.27 1.27)
							)
						)
					)
					(number "1"
						(effects
							(font
								(size 1.27 1.27)
							)
						)
					)
				)
				(pin passive line
					(at 5.08 0 180)
					(length 1.27)
					(name "~"
						(effects
							(font
								(size 1.27 1.27)
							)
						)
					)
					(number "2"
						(effects
							(font
								(size 1.27 1.27)
							)
						)
					)
				)
			)
		)
	(symbol "antmicroLEDIndicationDiscrete:LED_G_0603_LG_L29K-G2J1-24-Z"
			(pin_numbers
				(hide yes)
			)
			(pin_names
				(hide yes)
			)
			(exclude_from_sim no)
			(in_bom yes)
			(on_board yes)
			(property "Reference" "D"
				(at 20.32 -2.54 0)
				(effects
					(font
						(size 1.27 1.27)
						(thickness 0.15)
					)
					(justify left bottom)
				)
			)
			(property "Value" "LED_G_0603_LG_L29K-G2J1-24-Z"
				(at 20.32 -7.62 0)
				(effects
					(font
						(size 1.27 1.27)
						(thickness 0.15)
					)
					(justify left bottom)
					(hide yes)
				)
			)
			(property "Footprint" "antmicro-footprints:LED_0603_1608Metric_G"
				(at 20.32 -10.16 0)
				(effects
					(font
						(size 1.27 1.27)
						(thickness 0.15)
					)
					(justify left bottom)
					(hide yes)
				)
			)
			(property "Datasheet" "https://look.ams-osram.com/m/19ee86b3ae0ee95b/original/LG-L29K.pdf"
				(at 20.32 -12.7 0)
				(effects
					(font
						(size 1.27 1.27)
						(thickness 0.15)
					)
					(justify left bottom)
					(hide yes)
				)
			)
			(property "Description" "LED, Green, SMD, 0603, 20 mA, 1.7 V, 570 nm"
				(at 0 0 0)
				(effects
					(font
						(size 1.27 1.27)
					)
					(hide yes)
				)
			)
			(property "MPN" "LG L29K-G2J1-24-Z"
				(at 20.32 -15.24 0)
				(effects
					(font
						(size 1.27 1.27)
						(thickness 0.15)
					)
					(justify left bottom)
					(hide yes)
				)
			)
			(property "Manufacturer" "OSRAM"
				(at 20.32 -17.78 0)
				(effects
					(font
						(size 1.27 1.27)
						(thickness 0.15)
					)
					(justify left bottom)
					(hide yes)
				)
			)
			(property "Color" "Green"
				(at 20.32 -5.08 0)
				(effects
					(font
						(size 1.27 1.27)
					)
					(justify left bottom)
				)
			)
			(property "Author" "Antmicro"
				(at 20.32 -20.32 0)
				(effects
					(font
						(size 1.27 1.27)
						(thickness 0.15)
					)
					(justify left bottom)
					(hide yes)
				)
			)
			(property "License" "Apache-2.0"
				(at 20.32 -22.86 0)
				(effects
					(font
						(size 1.27 1.27)
						(thickness 0.15)
					)
					(justify left bottom)
					(hide yes)
				)
			)
			(property "ki_keywords" "SMT, DIODE, SEMICONDUCTOR, LED"
				(at 0 0 0)
				(effects
					(font
						(size 1.27 1.27)
					)
					(hide yes)
				)
			)
			(symbol "LED_G_0603_LG_L29K-G2J1-24-Z_0_1"
				(polyline
					(pts
						(xy 1.905 0) (xy 0.635 0)
					)
					(stroke
						(width 0)
						(type default)
					)
					(fill
						(type none)
					)
				)
				(polyline
					(pts
						(xy 4.445 0) (xy 3.175 0)
					)
					(stroke
						(width 0)
						(type default)
					)
					(fill
						(type none)
					)
				)
			)
			(symbol "LED_G_0603_LG_L29K-G2J1-24-Z_1_1"
				(polyline
					(pts
						(xy 1.143 2.286) (xy 1.143 1.778) (xy 1.143 2.286) (xy 1.651 2.286) (xy 1.143 2.286) (xy 2.159 1.27)
					)
					(stroke
						(width 0.254)
						(type default)
					)
					(fill
						(type none)
					)
				)
				(polyline
					(pts
						(xy 1.778 1.016) (xy 1.778 -1.016)
					)
					(stroke
						(width 0.254)
						(type default)
					)
					(fill
						(type none)
					)
				)
				(polyline
					(pts
						(xy 2.159 2.54) (xy 2.159 2.032) (xy 2.159 2.54) (xy 2.667 2.54) (xy 2.159 2.54) (xy 3.048 1.651)
					)
					(stroke
						(width 0.254)
						(type default)
					)
					(fill
						(type none)
					)
				)
				(polyline
					(pts
						(xy 3.302 1.016) (xy 3.302 -1.016) (xy 1.778 0) (xy 3.302 1.016)
					)
					(stroke
						(width 0.254)
						(type default)
					)
					(fill
						(type outline)
					)
				)
				(pin passive line
					(at 0 0 0)
					(length 0.635)
					(name "C"
						(effects
							(font
								(size 1.27 1.27)
							)
						)
					)
					(number "1"
						(effects
							(font
								(size 1.27 1.27)
							)
						)
					)
				)
				(pin passive line
					(at 5.08 0 180)
					(length 0.635)
					(name "A"
						(effects
							(font
								(size 1.27 1.27)
							)
						)
					)
					(number "2"
						(effects
							(font
								(size 1.27 1.27)
							)
						)
					)
				)
			)
		)
	(symbol "antmicroMechanicalParts:MP_Pad3.5mm_Drill2.2mm"
			(pin_names
				(hide yes)
			)
			(exclude_from_sim no)
			(in_bom no)
			(on_board yes)
			(property "Reference" "MP"
				(at 15.24 -5.08 0)
				(effects
					(font
						(size 1.27 1.27)
						(thickness 0.15)
					)
					(justify left bottom)
				)
			)
			(property "Value" "MP_Pad3.5mm_Drill2.2mm"
				(at 15.24 -7.62 0)
				(effects
					(font
						(size 1.27 1.27)
						(thickness 0.15)
					)
					(justify left bottom)
				)
			)
			(property "Footprint" "antmicro-footprints:MP_Pad3.5mm_Drill2.2mm"
				(at 15.24 -10.16 0)
				(effects
					(font
						(size 1.27 1.27)
						(thickness 0.15)
					)
					(justify left bottom)
					(hide yes)
				)
			)
			(property "Datasheet" ""
				(at 16.84 -15.57 0)
				(effects
					(font
						(size 1.27 1.27)
						(thickness 0.15)
					)
					(justify left bottom)
					(hide yes)
				)
			)
			(property "Description" "PCB mounting point"
				(at 0 0 0)
				(effects
					(font
						(size 1.27 1.27)
					)
					(hide yes)
				)
			)
			(property "Author" "Antmicro"
				(at 15.24 -15.24 0)
				(effects
					(font
						(size 1.27 1.27)
						(thickness 0.15)
					)
					(justify left bottom)
					(hide yes)
				)
			)
			(property "License" "Apache-2.0"
				(at 15.24 -17.78 0)
				(effects
					(font
						(size 1.27 1.27)
						(thickness 0.15)
					)
					(justify left bottom)
					(hide yes)
				)
			)
			(property "ki_keywords" "MECHANICAL"
				(at 0 0 0)
				(effects
					(font
						(size 1.27 1.27)
					)
					(hide yes)
				)
			)
			(symbol "MP_Pad3.5mm_Drill2.2mm_1_1"
				(circle
					(center 5.08 0)
					(radius 1.27)
					(stroke
						(width 0.254)
						(type default)
					)
					(fill
						(type background)
					)
				)
				(circle
					(center 5.08 0)
					(radius 2.54)
					(stroke
						(width 0.254)
						(type default)
					)
					(fill
						(type background)
					)
				)
				(pin passive line
					(at 0 0 0)
					(length 2.54)
					(name "~"
						(effects
							(font
								(size 1.27 1.27)
							)
						)
					)
					(number "1"
						(effects
							(font
								(size 1.27 1.27)
							)
						)
					)
				)
			)
		)
	(symbol "antmicroPMICPowerDistributionSwitchesLoadDrivers:STUSB4500_QFN"
			(exclude_from_sim no)
			(in_bom yes)
			(on_board yes)
			(property "Reference" "U"
				(at 45.72 -3.81 0)
				(effects
					(font
						(size 1.27 1.27)
						(thickness 0.15)
					)
					(justify left bottom)
				)
			)
			(property "Value" "STUSB4500_QFN"
				(at 45.72 -8.89 0)
				(effects
					(font
						(size 1.27 1.27)
						(thickness 0.15)
					)
					(justify left bottom)
					(hide yes)
				)
			)
			(property "Footprint" "antmicro-footprints:QFN-24-1EP_4x4mm_P0.5_EP2.1x2.1mm"
				(at 45.72 -11.43 0)
				(effects
					(font
						(size 1.27 1.27)
						(thickness 0.15)
					)
					(justify left bottom)
					(hide yes)
				)
			)
			(property "Datasheet" "https://www.mouser.com/datasheet/2/389/dm00489312-1799262.pdf"
				(at 45.72 -13.97 0)
				(effects
					(font
						(size 1.27 1.27)
						(thickness 0.15)
					)
					(justify left bottom)
					(hide yes)
				)
			)
			(property "Description" "USB Controller USB 2.0 I2C Interface 24-QFN (4x4)"
				(at 0 0 0)
				(effects
					(font
						(size 1.27 1.27)
					)
					(hide yes)
				)
			)
			(property "MPN" "STUSB4500QTR"
				(at 45.72 -6.35 0)
				(effects
					(font
						(size 1.27 1.27)
						(thickness 0.15)
					)
					(justify left bottom)
				)
			)
			(property "Manufacturer" "STMicroelectronics"
				(at 45.72 -16.51 0)
				(effects
					(font
						(size 1.27 1.27)
						(thickness 0.15)
					)
					(justify left bottom)
					(hide yes)
				)
			)
			(property "Author" "Antmicro"
				(at 45.72 -19.05 0)
				(effects
					(font
						(size 1.27 1.27)
						(thickness 0.15)
					)
					(justify left bottom)
					(hide yes)
				)
			)
			(property "License" "Apache-2.0"
				(at 45.72 -21.59 0)
				(effects
					(font
						(size 1.27 1.27)
						(thickness 0.15)
					)
					(justify left bottom)
					(hide yes)
				)
			)
			(property "ki_keywords" "CONTROLLER"
				(at 0 0 0)
				(effects
					(font
						(size 1.27 1.27)
					)
					(hide yes)
				)
			)
			(symbol "STUSB4500_QFN_1_1"
				(rectangle
					(start 2.54 2.54)
					(end 27.94 -40.64)
					(stroke
						(width 0.254)
						(type default)
					)
					(fill
						(type background)
					)
				)
				(pin power_in line
					(at 0 0 0)
					(length 2.54)
					(name "VDD"
						(effects
							(font
								(size 1.27 1.27)
							)
						)
					)
					(number "24"
						(effects
							(font
								(size 1.27 1.27)
							)
						)
					)
				)
				(pin power_in line
					(at 0 -2.54 0)
					(length 2.54)
					(name "VSYS"
						(effects
							(font
								(size 1.27 1.27)
							)
						)
					)
					(number "22"
						(effects
							(font
								(size 1.27 1.27)
							)
						)
					)
				)
				(pin bidirectional line
					(at 0 -5.08 0)
					(length 2.54)
					(name "DISCH"
						(effects
							(font
								(size 1.27 1.27)
							)
						)
					)
					(number "9"
						(effects
							(font
								(size 1.27 1.27)
							)
						)
					)
				)
				(pin input line
					(at 0 -10.16 0)
					(length 2.54)
					(name "RESET"
						(effects
							(font
								(size 1.27 1.27)
							)
						)
					)
					(number "6"
						(effects
							(font
								(size 1.27 1.27)
							)
						)
					)
				)
				(pin bidirectional line
					(at 0 -15.24 0)
					(length 2.54)
					(name "CC1DB"
						(effects
							(font
								(size 1.27 1.27)
							)
						)
					)
					(number "1"
						(effects
							(font
								(size 1.27 1.27)
							)
						)
					)
				)
				(pin bidirectional line
					(at 0 -17.78 0)
					(length 2.54)
					(name "CC1"
						(effects
							(font
								(size 1.27 1.27)
							)
						)
					)
					(number "2"
						(effects
							(font
								(size 1.27 1.27)
							)
						)
					)
				)
				(pin bidirectional line
					(at 0 -20.32 0)
					(length 2.54)
					(name "CC2"
						(effects
							(font
								(size 1.27 1.27)
							)
						)
					)
					(number "4"
						(effects
							(font
								(size 1.27 1.27)
							)
						)
					)
				)
				(pin bidirectional line
					(at 0 -22.86 0)
					(length 2.54)
					(name "CC2DB"
						(effects
							(font
								(size 1.27 1.27)
							)
						)
					)
					(number "5"
						(effects
							(font
								(size 1.27 1.27)
							)
						)
					)
				)
				(pin input line
					(at 0 -27.94 0)
					(length 2.54)
					(name "SCL"
						(effects
							(font
								(size 1.27 1.27)
							)
						)
					)
					(number "7"
						(effects
							(font
								(size 1.27 1.27)
							)
						)
					)
				)
				(pin bidirectional line
					(at 0 -30.48 0)
					(length 2.54)
					(name "SDA"
						(effects
							(font
								(size 1.27 1.27)
							)
						)
					)
					(number "8"
						(effects
							(font
								(size 1.27 1.27)
							)
						)
					)
				)
				(pin output line
					(at 0 -33.02 0)
					(length 2.54)
					(name "~{ALERT}"
						(effects
							(font
								(size 1.27 1.27)
							)
						)
					)
					(number "19"
						(effects
							(font
								(size 1.27 1.27)
							)
						)
					)
				)
				(pin input line
					(at 0 -35.56 0)
					(length 2.54)
					(name "ADDR0"
						(effects
							(font
								(size 1.27 1.27)
							)
						)
					)
					(number "12"
						(effects
							(font
								(size 1.27 1.27)
							)
						)
					)
				)
				(pin input line
					(at 0 -38.1 0)
					(length 2.54)
					(name "ADDR1"
						(effects
							(font
								(size 1.27 1.27)
							)
						)
					)
					(number "13"
						(effects
							(font
								(size 1.27 1.27)
							)
						)
					)
				)
				(pin no_connect line
					(at 27.94 -31.75 180)
					(length 2.54)
					(hide yes)
					(name "NC"
						(effects
							(font
								(size 1.27 1.27)
							)
						)
					)
					(number "3"
						(effects
							(font
								(size 1.27 1.27)
							)
						)
					)
				)
				(pin output line
					(at 30.48 0 180)
					(length 2.54)
					(name "VBUS_EN_SNK"
						(effects
							(font
								(size 1.27 1.27)
							)
						)
					)
					(number "16"
						(effects
							(font
								(size 1.27 1.27)
							)
						)
					)
				)
				(pin input line
					(at 30.48 -2.54 180)
					(length 2.54)
					(name "VBUS_VS_DISCH"
						(effects
							(font
								(size 1.27 1.27)
							)
						)
					)
					(number "18"
						(effects
							(font
								(size 1.27 1.27)
							)
						)
					)
				)
				(pin output line
					(at 30.48 -7.62 180)
					(length 2.54)
					(name "GPIO"
						(effects
							(font
								(size 1.27 1.27)
							)
						)
					)
					(number "15"
						(effects
							(font
								(size 1.27 1.27)
							)
						)
					)
				)
				(pin output line
					(at 30.48 -10.16 180)
					(length 2.54)
					(name "ATTACH"
						(effects
							(font
								(size 1.27 1.27)
							)
						)
					)
					(number "11"
						(effects
							(font
								(size 1.27 1.27)
							)
						)
					)
				)
				(pin output line
					(at 30.48 -12.7 180)
					(length 2.54)
					(name "A_B_SIDE"
						(effects
							(font
								(size 1.27 1.27)
							)
						)
					)
					(number "17"
						(effects
							(font
								(size 1.27 1.27)
							)
						)
					)
				)
				(pin output line
					(at 30.48 -17.78 180)
					(length 2.54)
					(name "POWER_OK2"
						(effects
							(font
								(size 1.27 1.27)
							)
						)
					)
					(number "20"
						(effects
							(font
								(size 1.27 1.27)
							)
						)
					)
				)
				(pin output line
					(at 30.48 -20.32 180)
					(length 2.54)
					(name "POWER_OK3"
						(effects
							(font
								(size 1.27 1.27)
							)
						)
					)
					(number "14"
						(effects
							(font
								(size 1.27 1.27)
							)
						)
					)
				)
				(pin output line
					(at 30.48 -25.4 180)
					(length 2.54)
					(name "VREG_1V2"
						(effects
							(font
								(size 1.27 1.27)
							)
						)
					)
					(number "21"
						(effects
							(font
								(size 1.27 1.27)
							)
						)
					)
				)
				(pin output line
					(at 30.48 -27.94 180)
					(length 2.54)
					(name "VREG_2V7"
						(effects
							(font
								(size 1.27 1.27)
							)
						)
					)
					(number "23"
						(effects
							(font
								(size 1.27 1.27)
							)
						)
					)
				)
				(pin power_in line
					(at 30.48 -35.56 180)
					(length 2.54)
					(name "GND"
						(effects
							(font
								(size 1.27 1.27)
							)
						)
					)
					(number "10"
						(effects
							(font
								(size 1.27 1.27)
							)
						)
					)
				)
				(pin power_in line
					(at 30.48 -38.1 180)
					(length 2.54)
					(name "EP"
						(effects
							(font
								(size 1.27 1.27)
							)
						)
					)
					(number "25"
						(effects
							(font
								(size 1.27 1.27)
							)
						)
					)
				)
			)
		)
	(symbol "antmicroResistors0402:R_0R_0402"
			(pin_numbers
				(hide yes)
			)
			(pin_names
				(hide yes)
			)
			(exclude_from_sim no)
			(in_bom yes)
			(on_board yes)
			(property "Reference" "R"
				(at 20.32 -5.08 0)
				(effects
					(font
						(size 1.27 1.27)
						(thickness 0.15)
					)
					(justify left bottom)
				)
			)
			(property "Value" "R_0R_0402"
				(at 20.32 -12.7 0)
				(effects
					(font
						(size 1.27 1.27)
						(thickness 0.15)
					)
					(justify left bottom)
					(hide yes)
				)
			)
			(property "Footprint" "antmicro-footprints:R_0402_1005Metric"
				(at 20.32 -15.24 0)
				(effects
					(font
						(size 1.27 1.27)
						(thickness 0.15)
					)
					(justify left bottom)
					(hide yes)
				)
			)
			(property "Datasheet" "https://industrial.panasonic.com/cdbs/www-data/pdf/RDA0000/AOA0000C301.pdf"
				(at 20.32 -17.78 0)
				(effects
					(font
						(size 1.27 1.27)
						(thickness 0.15)
					)
					(justify left bottom)
					(hide yes)
				)
			)
			(property "Description" "SMD Chip Resistor, Jumper, 0 ohm, 100 mW, 0402 [1005 Metric], Thick Film, General Purpose"
				(at 0 0 0)
				(effects
					(font
						(size 1.27 1.27)
					)
					(hide yes)
				)
			)
			(property "MPN" "ERJ2GE0R00X"
				(at 20.32 -20.32 0)
				(effects
					(font
						(size 1.27 1.27)
						(thickness 0.15)
					)
					(justify left bottom)
					(hide yes)
				)
			)
			(property "Manufacturer" "Panasonic"
				(at 20.32 -22.86 0)
				(effects
					(font
						(size 1.27 1.27)
						(thickness 0.15)
					)
					(justify left bottom)
					(hide yes)
				)
			)
			(property "License" "Apache-2.0"
				(at 20.32 -25.4 0)
				(effects
					(font
						(size 1.27 1.27)
						(thickness 0.15)
					)
					(justify left bottom)
					(hide yes)
				)
			)
			(property "Author" "Antmicro"
				(at 20.32 -27.94 0)
				(effects
					(font
						(size 1.27 1.27)
						(thickness 0.15)
					)
					(justify left bottom)
					(hide yes)
				)
			)
			(property "Val" "0R"
				(at 20.32 -7.62 0)
				(effects
					(font
						(size 1.27 1.27)
						(thickness 0.15)
					)
					(justify left bottom)
				)
			)
			(property "Tolerance" "~"
				(at 20.32 -10.16 0)
				(effects
					(font
						(size 1.27 1.27)
					)
					(justify left bottom)
					(hide yes)
				)
			)
			(property "Current" "1A"
				(at 20.32 -30.48 0)
				(effects
					(font
						(size 1.27 1.27)
						(thickness 0.15)
					)
					(justify left bottom)
					(hide yes)
				)
			)
			(property "ki_keywords" "0402, SMT, RESISTOR, PASSIVE"
				(at 0 0 0)
				(effects
					(font
						(size 1.27 1.27)
					)
					(hide yes)
				)
			)
			(symbol "R_0R_0402_0_1"
				(rectangle
					(start 0.635 0.889)
					(end 4.445 -0.889)
					(stroke
						(width 0.254)
						(type default)
					)
					(fill
						(type none)
					)
				)
			)
			(symbol "R_0R_0402_1_1"
				(pin passive line
					(at 0 0 0)
					(length 0.635)
					(name "~"
						(effects
							(font
								(size 1.27 1.27)
							)
						)
					)
					(number "1"
						(effects
							(font
								(size 1.27 1.27)
							)
						)
					)
				)
				(pin passive line
					(at 5.08 0 180)
					(length 0.635)
					(name "~"
						(effects
							(font
								(size 1.27 1.27)
							)
						)
					)
					(number "2"
						(effects
							(font
								(size 1.27 1.27)
							)
						)
					)
				)
			)
		)
	(symbol "antmicroResistors0402:R_100R_0402"
			(pin_numbers
				(hide yes)
			)
			(pin_names
				(hide yes)
			)
			(exclude_from_sim no)
			(in_bom yes)
			(on_board yes)
			(property "Reference" "R"
				(at 20.32 -5.08 0)
				(effects
					(font
						(size 1.27 1.27)
						(thickness 0.15)
					)
					(justify left bottom)
				)
			)
			(property "Value" "R_100R_0402"
				(at 20.32 -12.7 0)
				(effects
					(font
						(size 1.27 1.27)
						(thickness 0.15)
					)
					(justify left bottom)
					(hide yes)
				)
			)
			(property "Footprint" "antmicro-footprints:R_0402_1005Metric"
				(at 20.32 -15.24 0)
				(effects
					(font
						(size 1.27 1.27)
						(thickness 0.15)
					)
					(justify left bottom)
					(hide yes)
				)
			)
			(property "Datasheet" "https://www.bourns.com/docs/product-datasheets/cr.pdf"
				(at 20.32 -17.78 0)
				(effects
					(font
						(size 1.27 1.27)
						(thickness 0.15)
					)
					(justify left bottom)
					(hide yes)
				)
			)
			(property "Description" "SMD Chip Resistor, 100 ohm, ± 1%, 62.5 mW, 0402 [1005 Metric], Thick Film, General Purpose"
				(at 0 0 0)
				(effects
					(font
						(size 1.27 1.27)
					)
					(hide yes)
				)
			)
			(property "MPN" "CR0402-FX-1000GLF"
				(at 20.32 -20.32 0)
				(effects
					(font
						(size 1.27 1.27)
						(thickness 0.15)
					)
					(justify left bottom)
					(hide yes)
				)
			)
			(property "Manufacturer" "Bourns"
				(at 20.32 -22.86 0)
				(effects
					(font
						(size 1.27 1.27)
						(thickness 0.15)
					)
					(justify left bottom)
					(hide yes)
				)
			)
			(property "License" "Apache-2.0"
				(at 20.32 -25.4 0)
				(effects
					(font
						(size 1.27 1.27)
						(thickness 0.15)
					)
					(justify left bottom)
					(hide yes)
				)
			)
			(property "Author" "Antmicro"
				(at 20.32 -27.94 0)
				(effects
					(font
						(size 1.27 1.27)
						(thickness 0.15)
					)
					(justify left bottom)
					(hide yes)
				)
			)
			(property "Val" "100R"
				(at 20.32 -7.62 0)
				(effects
					(font
						(size 1.27 1.27)
						(thickness 0.15)
					)
					(justify left bottom)
				)
			)
			(property "Tolerance" "1%"
				(at 20.32 -10.16 0)
				(effects
					(font
						(size 1.27 1.27)
					)
					(justify left bottom)
					(hide yes)
				)
			)
			(property "ki_keywords" "0402, SMT, RESISTOR, PASSIVE"
				(at 0 0 0)
				(effects
					(font
						(size 1.27 1.27)
					)
					(hide yes)
				)
			)
			(symbol "R_100R_0402_0_1"
				(rectangle
					(start 0.635 0.889)
					(end 4.445 -0.889)
					(stroke
						(width 0.254)
						(type default)
					)
					(fill
						(type none)
					)
				)
			)
			(symbol "R_100R_0402_1_1"
				(pin passive line
					(at 0 0 0)
					(length 0.635)
					(name "~"
						(effects
							(font
								(size 1.27 1.27)
							)
						)
					)
					(number "1"
						(effects
							(font
								(size 1.27 1.27)
							)
						)
					)
				)
				(pin passive line
					(at 5.08 0 180)
					(length 0.635)
					(name "~"
						(effects
							(font
								(size 1.27 1.27)
							)
						)
					)
					(number "2"
						(effects
							(font
								(size 1.27 1.27)
							)
						)
					)
				)
			)
		)
	(symbol "antmicroResistors0402:R_100k_0402"
			(pin_numbers
				(hide yes)
			)
			(pin_names
				(hide yes)
			)
			(exclude_from_sim no)
			(in_bom yes)
			(on_board yes)
			(property "Reference" "R"
				(at 20.32 -5.08 0)
				(effects
					(font
						(size 1.27 1.27)
						(thickness 0.15)
					)
					(justify left bottom)
				)
			)
			(property "Value" "R_100k_0402"
				(at 20.32 -12.7 0)
				(effects
					(font
						(size 1.27 1.27)
						(thickness 0.15)
					)
					(justify left bottom)
					(hide yes)
				)
			)
			(property "Footprint" "antmicro-footprints:R_0402_1005Metric"
				(at 20.32 -15.24 0)
				(effects
					(font
						(size 1.27 1.27)
						(thickness 0.15)
					)
					(justify left bottom)
					(hide yes)
				)
			)
			(property "Datasheet" "https://www.bourns.com/docs/product-datasheets/cr.pdf"
				(at 20.32 -17.78 0)
				(effects
					(font
						(size 1.27 1.27)
						(thickness 0.15)
					)
					(justify left bottom)
					(hide yes)
				)
			)
			(property "Description" "SMD Chip Resistor, 100 kohm, ± 1%, 62.5 mW, 0402 [1005 Metric], Thick Film, General Purpose"
				(at 0 0 0)
				(effects
					(font
						(size 1.27 1.27)
					)
					(hide yes)
				)
			)
			(property "MPN" "CR0402-FX-1003GLF"
				(at 20.32 -20.32 0)
				(effects
					(font
						(size 1.27 1.27)
						(thickness 0.15)
					)
					(justify left bottom)
					(hide yes)
				)
			)
			(property "Manufacturer" "Bourns"
				(at 20.32 -22.86 0)
				(effects
					(font
						(size 1.27 1.27)
						(thickness 0.15)
					)
					(justify left bottom)
					(hide yes)
				)
			)
			(property "License" "Apache-2.0"
				(at 20.32 -25.4 0)
				(effects
					(font
						(size 1.27 1.27)
						(thickness 0.15)
					)
					(justify left bottom)
					(hide yes)
				)
			)
			(property "Author" "Antmicro"
				(at 20.32 -27.94 0)
				(effects
					(font
						(size 1.27 1.27)
						(thickness 0.15)
					)
					(justify left bottom)
					(hide yes)
				)
			)
			(property "Val" "100k"
				(at 20.32 -7.62 0)
				(effects
					(font
						(size 1.27 1.27)
						(thickness 0.15)
					)
					(justify left bottom)
				)
			)
			(property "Tolerance" "1%"
				(at 20.32 -10.16 0)
				(effects
					(font
						(size 1.27 1.27)
					)
					(justify left bottom)
					(hide yes)
				)
			)
			(property "ki_keywords" "0402, SMT, RESISTOR, PASSIVE"
				(at 0 0 0)
				(effects
					(font
						(size 1.27 1.27)
					)
					(hide yes)
				)
			)
			(symbol "R_100k_0402_0_1"
				(rectangle
					(start 0.635 0.889)
					(end 4.445 -0.889)
					(stroke
						(width 0.254)
						(type default)
					)
					(fill
						(type none)
					)
				)
			)
			(symbol "R_100k_0402_1_1"
				(pin passive line
					(at 0 0 0)
					(length 0.635)
					(name "~"
						(effects
							(font
								(size 1.27 1.27)
							)
						)
					)
					(number "1"
						(effects
							(font
								(size 1.27 1.27)
							)
						)
					)
				)
				(pin passive line
					(at 5.08 0 180)
					(length 0.635)
					(name "~"
						(effects
							(font
								(size 1.27 1.27)
							)
						)
					)
					(number "2"
						(effects
							(font
								(size 1.27 1.27)
							)
						)
					)
				)
			)
		)
	(symbol "antmicroResistors0402:R_10k_0.1%_0402"
			(pin_numbers
				(hide yes)
			)
			(pin_names
				(hide yes)
			)
			(exclude_from_sim no)
			(in_bom yes)
			(on_board yes)
			(property "Reference" "R"
				(at 15.24 -5.08 0)
				(effects
					(font
						(size 1.27 1.27)
						(thickness 0.15)
					)
					(justify left bottom)
				)
			)
			(property "Value" "R_10k_0.1%_0402"
				(at 15.24 -12.7 0)
				(effects
					(font
						(size 1.27 1.27)
						(thickness 0.15)
					)
					(justify left bottom)
					(hide yes)
				)
			)
			(property "Footprint" "antmicro-footprints:R_0402_1005Metric"
				(at 15.24 -15.24 0)
				(effects
					(font
						(size 1.27 1.27)
						(thickness 0.15)
					)
					(justify left bottom)
					(hide yes)
				)
			)
			(property "Datasheet" "https://www.mouser.com/datasheet/2/54/CRT-1649066.pdf"
				(at 15.24 -17.78 0)
				(effects
					(font
						(size 1.27 1.27)
						(thickness 0.15)
					)
					(justify left bottom)
					(hide yes)
				)
			)
			(property "Description" "SMD Chip Resistor, 10 kohm, ± 0.1%, 62.5 mW, 0402 [1005 Metric], Thin Film, Precision Resistors"
				(at 0 0 0)
				(effects
					(font
						(size 1.27 1.27)
					)
					(hide yes)
				)
			)
			(property "MPN" "CRT0402-BY-1002GLF "
				(at 15.24 -20.32 0)
				(effects
					(font
						(size 1.27 1.27)
						(thickness 0.15)
					)
					(justify left bottom)
					(hide yes)
				)
			)
			(property "Val" "10k"
				(at 15.24 -7.62 0)
				(effects
					(font
						(size 1.27 1.27)
						(thickness 0.15)
					)
					(justify left bottom)
				)
			)
			(property "Tolerance" "0.1%"
				(at 15.24 -10.16 0)
				(effects
					(font
						(size 1.27 1.27)
						(thickness 0.15)
					)
					(justify left bottom)
					(hide yes)
				)
			)
			(property "Author" "Antmicro"
				(at 15.24 -22.86 0)
				(effects
					(font
						(size 1.27 1.27)
						(thickness 0.15)
					)
					(justify left bottom)
					(hide yes)
				)
			)
			(property "License" "Apache-2.0"
				(at 15.24 -25.4 0)
				(effects
					(font
						(size 1.27 1.27)
						(thickness 0.15)
					)
					(justify left bottom)
					(hide yes)
				)
			)
			(property "Manufacturer" "Bourns"
				(at 15.24 -27.94 0)
				(effects
					(font
						(size 1.27 1.27)
						(thickness 0.15)
					)
					(justify left bottom)
					(hide yes)
				)
			)
			(property "ki_keywords" "0402, SMT, RESISTOR, PASSIVE"
				(at 0 0 0)
				(effects
					(font
						(size 1.27 1.27)
					)
					(hide yes)
				)
			)
			(symbol "R_10k_0.1%_0402_0_1"
				(rectangle
					(start 0.635 0.889)
					(end 4.445 -0.889)
					(stroke
						(width 0.254)
						(type default)
					)
					(fill
						(type none)
					)
				)
			)
			(symbol "R_10k_0.1%_0402_1_1"
				(pin passive line
					(at 0 0 0)
					(length 0.635)
					(name "~"
						(effects
							(font
								(size 1.27 1.27)
							)
						)
					)
					(number "1"
						(effects
							(font
								(size 1.27 1.27)
							)
						)
					)
				)
				(pin passive line
					(at 5.08 0 180)
					(length 0.635)
					(name "~"
						(effects
							(font
								(size 1.27 1.27)
							)
						)
					)
					(number "2"
						(effects
							(font
								(size 1.27 1.27)
							)
						)
					)
				)
			)
		)
	(symbol "antmicroResistors0402:R_10k_0402"
			(pin_numbers
				(hide yes)
			)
			(pin_names
				(hide yes)
			)
			(exclude_from_sim no)
			(in_bom yes)
			(on_board yes)
			(property "Reference" "R"
				(at 20.32 -5.08 0)
				(effects
					(font
						(size 1.27 1.27)
						(thickness 0.15)
					)
					(justify left bottom)
				)
			)
			(property "Value" "R_10k_0402"
				(at 20.32 -12.7 0)
				(effects
					(font
						(size 1.27 1.27)
						(thickness 0.15)
					)
					(justify left bottom)
					(hide yes)
				)
			)
			(property "Footprint" "antmicro-footprints:R_0402_1005Metric"
				(at 20.32 -15.24 0)
				(effects
					(font
						(size 1.27 1.27)
						(thickness 0.15)
					)
					(justify left bottom)
					(hide yes)
				)
			)
			(property "Datasheet" "https://www.bourns.com/docs/product-datasheets/cr.pdf"
				(at 20.32 -17.78 0)
				(effects
					(font
						(size 1.27 1.27)
						(thickness 0.15)
					)
					(justify left bottom)
					(hide yes)
				)
			)
			(property "Description" "SMD Chip Resistor, 10 kohm, ± 1%, 62.5 mW, 0402 [1005 Metric], Thick Film, General Purpose"
				(at 0 0 0)
				(effects
					(font
						(size 1.27 1.27)
					)
					(hide yes)
				)
			)
			(property "MPN" "CR0402-FX-1002GLF"
				(at 20.32 -20.32 0)
				(effects
					(font
						(size 1.27 1.27)
						(thickness 0.15)
					)
					(justify left bottom)
					(hide yes)
				)
			)
			(property "Manufacturer" "Bourns"
				(at 20.32 -22.86 0)
				(effects
					(font
						(size 1.27 1.27)
						(thickness 0.15)
					)
					(justify left bottom)
					(hide yes)
				)
			)
			(property "License" "Apache-2.0"
				(at 20.32 -25.4 0)
				(effects
					(font
						(size 1.27 1.27)
						(thickness 0.15)
					)
					(justify left bottom)
					(hide yes)
				)
			)
			(property "Author" "Antmicro"
				(at 20.32 -27.94 0)
				(effects
					(font
						(size 1.27 1.27)
						(thickness 0.15)
					)
					(justify left bottom)
					(hide yes)
				)
			)
			(property "Val" "10k"
				(at 20.32 -7.62 0)
				(effects
					(font
						(size 1.27 1.27)
						(thickness 0.15)
					)
					(justify left bottom)
				)
			)
			(property "Tolerance" "1%"
				(at 20.32 -10.16 0)
				(effects
					(font
						(size 1.27 1.27)
					)
					(justify left bottom)
					(hide yes)
				)
			)
			(property "ki_keywords" "0402, SMT, RESISTOR, PASSIVE"
				(at 0 0 0)
				(effects
					(font
						(size 1.27 1.27)
					)
					(hide yes)
				)
			)
			(symbol "R_10k_0402_0_1"
				(rectangle
					(start 0.635 0.889)
					(end 4.445 -0.889)
					(stroke
						(width 0.254)
						(type default)
					)
					(fill
						(type none)
					)
				)
			)
			(symbol "R_10k_0402_1_1"
				(pin passive line
					(at 0 0 0)
					(length 0.635)
					(name "~"
						(effects
							(font
								(size 1.27 1.27)
							)
						)
					)
					(number "1"
						(effects
							(font
								(size 1.27 1.27)
							)
						)
					)
				)
				(pin passive line
					(at 5.08 0 180)
					(length 0.635)
					(name "~"
						(effects
							(font
								(size 1.27 1.27)
							)
						)
					)
					(number "2"
						(effects
							(font
								(size 1.27 1.27)
							)
						)
					)
				)
			)
		)
	(symbol "antmicroResistors0402:R_140k_0.1%_0402"
			(pin_numbers
				(hide yes)
			)
			(pin_names
				(hide yes)
			)
			(exclude_from_sim no)
			(in_bom yes)
			(on_board yes)
			(property "Reference" "R"
				(at 15.24 -5.08 0)
				(effects
					(font
						(size 1.27 1.27)
						(thickness 0.15)
					)
					(justify left bottom)
				)
			)
			(property "Value" "R_140k_0.1%_0402"
				(at 15.24 -10.16 0)
				(effects
					(font
						(size 1.27 1.27)
						(thickness 0.15)
					)
					(justify left bottom)
					(hide yes)
				)
			)
			(property "Footprint" "antmicro-footprints:R_0402_1005Metric"
				(at 15.24 -12.7 0)
				(effects
					(font
						(size 1.27 1.27)
						(thickness 0.15)
					)
					(justify left bottom)
					(hide yes)
				)
			)
			(property "Datasheet" "https://www.vishay.com/docs/28758/tnpw_e3.pdf"
				(at 15.24 -15.24 0)
				(effects
					(font
						(size 1.27 1.27)
						(thickness 0.15)
					)
					(justify left bottom)
					(hide yes)
				)
			)
			(property "Description" "SMD Chip Resistor, Ceramic, 140 kohm, ± 0.1%, 62.5 mW, 0402 [1005 Metric], Thin Film, Precision resistors"
				(at 0 0 0)
				(effects
					(font
						(size 1.27 1.27)
					)
					(hide yes)
				)
			)
			(property "MPN" "RT0402BRD07140KL"
				(at 15.24 -17.78 0)
				(effects
					(font
						(size 1.27 1.27)
						(thickness 0.15)
					)
					(justify left bottom)
					(hide yes)
				)
			)
			(property "Val" "140k"
				(at 15.24 -7.62 0)
				(effects
					(font
						(size 1.27 1.27)
						(thickness 0.15)
					)
					(justify left bottom)
				)
			)
			(property "Tolerance" "0.1%"
				(at 15.24 -20.32 0)
				(effects
					(font
						(size 1.27 1.27)
						(thickness 0.15)
					)
					(justify left bottom)
					(hide yes)
				)
			)
			(property "Author" "Antmicro"
				(at 15.24 -22.86 0)
				(effects
					(font
						(size 1.27 1.27)
						(thickness 0.15)
					)
					(justify left bottom)
					(hide yes)
				)
			)
			(property "License" "Apache-2.0"
				(at 15.24 -25.4 0)
				(effects
					(font
						(size 1.27 1.27)
						(thickness 0.15)
					)
					(justify left bottom)
					(hide yes)
				)
			)
			(property "Manufacturer" "YAGEO"
				(at 15.24 -27.94 0)
				(effects
					(font
						(size 1.27 1.27)
						(thickness 0.15)
					)
					(justify left bottom)
					(hide yes)
				)
			)
			(property "ki_keywords" "0402, SMT, RESISTOR, PASSIVE"
				(at 0 0 0)
				(effects
					(font
						(size 1.27 1.27)
					)
					(hide yes)
				)
			)
			(symbol "R_140k_0.1%_0402_0_1"
				(rectangle
					(start 0.635 0.889)
					(end 4.445 -0.889)
					(stroke
						(width 0.254)
						(type default)
					)
					(fill
						(type none)
					)
				)
			)
			(symbol "R_140k_0.1%_0402_1_1"
				(pin passive line
					(at 0 0 0)
					(length 0.635)
					(name "~"
						(effects
							(font
								(size 1.27 1.27)
							)
						)
					)
					(number "1"
						(effects
							(font
								(size 1.27 1.27)
							)
						)
					)
				)
				(pin passive line
					(at 5.08 0 180)
					(length 0.635)
					(name "~"
						(effects
							(font
								(size 1.27 1.27)
							)
						)
					)
					(number "2"
						(effects
							(font
								(size 1.27 1.27)
							)
						)
					)
				)
			)
		)
	(symbol "antmicroResistors0402:R_158k_0402"
			(pin_numbers
				(hide yes)
			)
			(pin_names
				(hide yes)
			)
			(exclude_from_sim no)
			(in_bom yes)
			(on_board yes)
			(property "Reference" "R"
				(at 20.32 -5.08 0)
				(effects
					(font
						(size 1.27 1.27)
						(thickness 0.15)
					)
					(justify left bottom)
				)
			)
			(property "Value" "R_158k_0402"
				(at 20.32 -12.7 0)
				(effects
					(font
						(size 1.27 1.27)
						(thickness 0.15)
					)
					(justify left bottom)
					(hide yes)
				)
			)
			(property "Footprint" "antmicro-footprints:R_0402_1005Metric"
				(at 20.32 -15.24 0)
				(effects
					(font
						(size 1.27 1.27)
						(thickness 0.15)
					)
					(justify left bottom)
					(hide yes)
				)
			)
			(property "Datasheet" "https://www.bourns.com/docs/product-datasheets/cr.pdf"
				(at 20.32 -17.78 0)
				(effects
					(font
						(size 1.27 1.27)
						(thickness 0.15)
					)
					(justify left bottom)
					(hide yes)
				)
			)
			(property "Description" "SMD Chip Resistor, 158 kohm, ± 1%, 100 mW, 0402 [1005 Metric], Thick Film, Precision"
				(at 0 0 0)
				(effects
					(font
						(size 1.27 1.27)
					)
					(hide yes)
				)
			)
			(property "MPN" "CR0402-FX-1583GLF"
				(at 20.32 -20.32 0)
				(effects
					(font
						(size 1.27 1.27)
						(thickness 0.15)
					)
					(justify left bottom)
					(hide yes)
				)
			)
			(property "Manufacturer" "Bourns"
				(at 20.32 -22.86 0)
				(effects
					(font
						(size 1.27 1.27)
						(thickness 0.15)
					)
					(justify left bottom)
					(hide yes)
				)
			)
			(property "License" "Apache-2.0"
				(at 20.32 -25.4 0)
				(effects
					(font
						(size 1.27 1.27)
						(thickness 0.15)
					)
					(justify left bottom)
					(hide yes)
				)
			)
			(property "Author" "Antmicro"
				(at 20.32 -27.94 0)
				(effects
					(font
						(size 1.27 1.27)
						(thickness 0.15)
					)
					(justify left bottom)
					(hide yes)
				)
			)
			(property "Val" "158k"
				(at 20.32 -7.62 0)
				(effects
					(font
						(size 1.27 1.27)
						(thickness 0.15)
					)
					(justify left bottom)
				)
			)
			(property "Tolerance" "1%"
				(at 20.32 -10.16 0)
				(effects
					(font
						(size 1.27 1.27)
					)
					(justify left bottom)
					(hide yes)
				)
			)
			(property "ki_keywords" "0402, SMT, RESISTOR, PASSIVE"
				(at 0 0 0)
				(effects
					(font
						(size 1.27 1.27)
					)
					(hide yes)
				)
			)
			(symbol "R_158k_0402_0_1"
				(rectangle
					(start 0.635 0.889)
					(end 4.445 -0.889)
					(stroke
						(width 0.254)
						(type default)
					)
					(fill
						(type none)
					)
				)
			)
			(symbol "R_158k_0402_1_1"
				(pin passive line
					(at 0 0 0)
					(length 0.635)
					(name "~"
						(effects
							(font
								(size 1.27 1.27)
							)
						)
					)
					(number "1"
						(effects
							(font
								(size 1.27 1.27)
							)
						)
					)
				)
				(pin passive line
					(at 5.08 0 180)
					(length 0.635)
					(name "~"
						(effects
							(font
								(size 1.27 1.27)
							)
						)
					)
					(number "2"
						(effects
							(font
								(size 1.27 1.27)
							)
						)
					)
				)
			)
		)
	(symbol "antmicroResistors0402:R_15k_0402"
			(pin_numbers
				(hide yes)
			)
			(pin_names
				(hide yes)
			)
			(exclude_from_sim no)
			(in_bom yes)
			(on_board yes)
			(property "Reference" "R"
				(at 20.32 -5.08 0)
				(effects
					(font
						(size 1.27 1.27)
						(thickness 0.15)
					)
					(justify left bottom)
				)
			)
			(property "Value" "R_15k_0402"
				(at 20.32 -12.7 0)
				(effects
					(font
						(size 1.27 1.27)
						(thickness 0.15)
					)
					(justify left bottom)
					(hide yes)
				)
			)
			(property "Footprint" "antmicro-footprints:R_0402_1005Metric"
				(at 20.32 -15.24 0)
				(effects
					(font
						(size 1.27 1.27)
						(thickness 0.15)
					)
					(justify left bottom)
					(hide yes)
				)
			)
			(property "Datasheet" "https://www.bourns.com/docs/product-datasheets/cr.pdf"
				(at 20.32 -17.78 0)
				(effects
					(font
						(size 1.27 1.27)
						(thickness 0.15)
					)
					(justify left bottom)
					(hide yes)
				)
			)
			(property "Description" "SMD Chip Resistor, 15 kohm, ± 1%, 62.5 mW, 0402 [1005 Metric], Thick Film, General Purpose"
				(at 0 0 0)
				(effects
					(font
						(size 1.27 1.27)
					)
					(hide yes)
				)
			)
			(property "MPN" "CR0402-FX-1502GLF"
				(at 20.32 -20.32 0)
				(effects
					(font
						(size 1.27 1.27)
						(thickness 0.15)
					)
					(justify left bottom)
					(hide yes)
				)
			)
			(property "Manufacturer" "Bourns"
				(at 20.32 -22.86 0)
				(effects
					(font
						(size 1.27 1.27)
						(thickness 0.15)
					)
					(justify left bottom)
					(hide yes)
				)
			)
			(property "License" "Apache-2.0"
				(at 20.32 -25.4 0)
				(effects
					(font
						(size 1.27 1.27)
						(thickness 0.15)
					)
					(justify left bottom)
					(hide yes)
				)
			)
			(property "Author" "Antmicro"
				(at 20.32 -27.94 0)
				(effects
					(font
						(size 1.27 1.27)
						(thickness 0.15)
					)
					(justify left bottom)
					(hide yes)
				)
			)
			(property "Val" "15k"
				(at 20.32 -7.62 0)
				(effects
					(font
						(size 1.27 1.27)
						(thickness 0.15)
					)
					(justify left bottom)
				)
			)
			(property "Tolerance" "1%"
				(at 20.32 -10.16 0)
				(effects
					(font
						(size 1.27 1.27)
					)
					(justify left bottom)
					(hide yes)
				)
			)
			(property "ki_keywords" "0402, SMT, RESISTOR, PASSIVE"
				(at 0 0 0)
				(effects
					(font
						(size 1.27 1.27)
					)
					(hide yes)
				)
			)
			(symbol "R_15k_0402_0_1"
				(rectangle
					(start 0.635 0.889)
					(end 4.445 -0.889)
					(stroke
						(width 0.254)
						(type default)
					)
					(fill
						(type none)
					)
				)
			)
			(symbol "R_15k_0402_1_1"
				(pin passive line
					(at 0 0 0)
					(length 0.635)
					(name "~"
						(effects
							(font
								(size 1.27 1.27)
							)
						)
					)
					(number "1"
						(effects
							(font
								(size 1.27 1.27)
							)
						)
					)
				)
				(pin passive line
					(at 5.08 0 180)
					(length 0.635)
					(name "~"
						(effects
							(font
								(size 1.27 1.27)
							)
						)
					)
					(number "2"
						(effects
							(font
								(size 1.27 1.27)
							)
						)
					)
				)
			)
		)
	(symbol "antmicroResistors0402:R_1k2_0402"
			(pin_numbers
				(hide yes)
			)
			(pin_names
				(hide yes)
			)
			(exclude_from_sim no)
			(in_bom yes)
			(on_board yes)
			(property "Reference" "R"
				(at 20.32 -5.08 0)
				(effects
					(font
						(size 1.27 1.27)
						(thickness 0.15)
					)
					(justify left bottom)
				)
			)
			(property "Value" "R_1k2_0402"
				(at 20.32 -12.7 0)
				(effects
					(font
						(size 1.27 1.27)
						(thickness 0.15)
					)
					(justify left bottom)
					(hide yes)
				)
			)
			(property "Footprint" "antmicro-footprints:R_0402_1005Metric"
				(at 20.32 -15.24 0)
				(effects
					(font
						(size 1.27 1.27)
						(thickness 0.15)
					)
					(justify left bottom)
					(hide yes)
				)
			)
			(property "Datasheet" "https://www.bourns.com/docs/product-datasheets/cr.pdf"
				(at 20.32 -17.78 0)
				(effects
					(font
						(size 1.27 1.27)
						(thickness 0.15)
					)
					(justify left bottom)
					(hide yes)
				)
			)
			(property "Description" "SMD Chip Resistor, 1.2 kohm, ± 1%, 62.5 mW, 0402 [1005 Metric], Thick Film, General Purpose"
				(at 0 0 0)
				(effects
					(font
						(size 1.27 1.27)
					)
					(hide yes)
				)
			)
			(property "MPN" "CR0402-FX-1201GLF"
				(at 20.32 -20.32 0)
				(effects
					(font
						(size 1.27 1.27)
						(thickness 0.15)
					)
					(justify left bottom)
					(hide yes)
				)
			)
			(property "Manufacturer" "Bourns"
				(at 20.32 -22.86 0)
				(effects
					(font
						(size 1.27 1.27)
						(thickness 0.15)
					)
					(justify left bottom)
					(hide yes)
				)
			)
			(property "License" "Apache-2.0"
				(at 20.32 -25.4 0)
				(effects
					(font
						(size 1.27 1.27)
						(thickness 0.15)
					)
					(justify left bottom)
					(hide yes)
				)
			)
			(property "Author" "Antmicro"
				(at 20.32 -27.94 0)
				(effects
					(font
						(size 1.27 1.27)
						(thickness 0.15)
					)
					(justify left bottom)
					(hide yes)
				)
			)
			(property "Val" "1k2"
				(at 20.32 -7.62 0)
				(effects
					(font
						(size 1.27 1.27)
						(thickness 0.15)
					)
					(justify left bottom)
				)
			)
			(property "Tolerance" "1%"
				(at 20.32 -10.16 0)
				(effects
					(font
						(size 1.27 1.27)
					)
					(justify left bottom)
					(hide yes)
				)
			)
			(property "ki_keywords" "0402, SMT, RESISTOR, PASSIVE"
				(at 0 0 0)
				(effects
					(font
						(size 1.27 1.27)
					)
					(hide yes)
				)
			)
			(symbol "R_1k2_0402_0_1"
				(rectangle
					(start 0.635 0.889)
					(end 4.445 -0.889)
					(stroke
						(width 0.254)
						(type default)
					)
					(fill
						(type none)
					)
				)
			)
			(symbol "R_1k2_0402_1_1"
				(pin passive line
					(at 0 0 0)
					(length 0.635)
					(name "~"
						(effects
							(font
								(size 1.27 1.27)
							)
						)
					)
					(number "1"
						(effects
							(font
								(size 1.27 1.27)
							)
						)
					)
				)
				(pin passive line
					(at 5.08 0 180)
					(length 0.635)
					(name "~"
						(effects
							(font
								(size 1.27 1.27)
							)
						)
					)
					(number "2"
						(effects
							(font
								(size 1.27 1.27)
							)
						)
					)
				)
			)
		)
	(symbol "antmicroResistors0402:R_1k_0402"
			(pin_numbers
				(hide yes)
			)
			(pin_names
				(hide yes)
			)
			(exclude_from_sim no)
			(in_bom yes)
			(on_board yes)
			(property "Reference" "R"
				(at 20.32 -5.08 0)
				(effects
					(font
						(size 1.27 1.27)
						(thickness 0.15)
					)
					(justify left bottom)
				)
			)
			(property "Value" "R_1k_0402"
				(at 20.32 -12.7 0)
				(effects
					(font
						(size 1.27 1.27)
						(thickness 0.15)
					)
					(justify left bottom)
					(hide yes)
				)
			)
			(property "Footprint" "antmicro-footprints:R_0402_1005Metric"
				(at 20.32 -15.24 0)
				(effects
					(font
						(size 1.27 1.27)
						(thickness 0.15)
					)
					(justify left bottom)
					(hide yes)
				)
			)
			(property "Datasheet" "https://www.bourns.com/docs/product-datasheets/cr.pdf"
				(at 20.32 -17.78 0)
				(effects
					(font
						(size 1.27 1.27)
						(thickness 0.15)
					)
					(justify left bottom)
					(hide yes)
				)
			)
			(property "Description" "SMD Chip Resistor, 1 kohm, ± 1%, 63 mW, 0402 [1005 Metric], Thick Film, General Purpose"
				(at 0 0 0)
				(effects
					(font
						(size 1.27 1.27)
					)
					(hide yes)
				)
			)
			(property "MPN" "CR0402-FX-1001GLF"
				(at 20.32 -20.32 0)
				(effects
					(font
						(size 1.27 1.27)
						(thickness 0.15)
					)
					(justify left bottom)
					(hide yes)
				)
			)
			(property "Manufacturer" "Bourns"
				(at 20.32 -22.86 0)
				(effects
					(font
						(size 1.27 1.27)
						(thickness 0.15)
					)
					(justify left bottom)
					(hide yes)
				)
			)
			(property "License" "Apache-2.0"
				(at 20.32 -25.4 0)
				(effects
					(font
						(size 1.27 1.27)
						(thickness 0.15)
					)
					(justify left bottom)
					(hide yes)
				)
			)
			(property "Author" "Antmicro"
				(at 20.32 -27.94 0)
				(effects
					(font
						(size 1.27 1.27)
						(thickness 0.15)
					)
					(justify left bottom)
					(hide yes)
				)
			)
			(property "Val" "1k"
				(at 20.32 -7.62 0)
				(effects
					(font
						(size 1.27 1.27)
						(thickness 0.15)
					)
					(justify left bottom)
				)
			)
			(property "Tolerance" "1%"
				(at 20.32 -10.16 0)
				(effects
					(font
						(size 1.27 1.27)
					)
					(justify left bottom)
					(hide yes)
				)
			)
			(property "ki_keywords" "0402, SMT, RESISTOR, PASSIVE"
				(at 0 0 0)
				(effects
					(font
						(size 1.27 1.27)
					)
					(hide yes)
				)
			)
			(symbol "R_1k_0402_0_1"
				(rectangle
					(start 0.635 0.889)
					(end 4.445 -0.889)
					(stroke
						(width 0.254)
						(type default)
					)
					(fill
						(type none)
					)
				)
			)
			(symbol "R_1k_0402_1_1"
				(pin passive line
					(at 0 0 0)
					(length 0.635)
					(name "~"
						(effects
							(font
								(size 1.27 1.27)
							)
						)
					)
					(number "1"
						(effects
							(font
								(size 1.27 1.27)
							)
						)
					)
				)
				(pin passive line
					(at 5.08 0 180)
					(length 0.635)
					(name "~"
						(effects
							(font
								(size 1.27 1.27)
							)
						)
					)
					(number "2"
						(effects
							(font
								(size 1.27 1.27)
							)
						)
					)
				)
			)
		)
	(symbol "antmicroResistors0402:R_220R_0402"
			(pin_numbers
				(hide yes)
			)
			(pin_names
				(hide yes)
			)
			(exclude_from_sim no)
			(in_bom yes)
			(on_board yes)
			(property "Reference" "R"
				(at 20.32 -5.08 0)
				(effects
					(font
						(size 1.27 1.27)
						(thickness 0.15)
					)
					(justify left bottom)
				)
			)
			(property "Value" "R_220R_0402"
				(at 20.32 -12.7 0)
				(effects
					(font
						(size 1.27 1.27)
						(thickness 0.15)
					)
					(justify left bottom)
					(hide yes)
				)
			)
			(property "Footprint" "antmicro-footprints:R_0402_1005Metric"
				(at 20.32 -15.24 0)
				(effects
					(font
						(size 1.27 1.27)
						(thickness 0.15)
					)
					(justify left bottom)
					(hide yes)
				)
			)
			(property "Datasheet" "https://www.bourns.com/docs/product-datasheets/cr.pdf"
				(at 20.32 -17.78 0)
				(effects
					(font
						(size 1.27 1.27)
						(thickness 0.15)
					)
					(justify left bottom)
					(hide yes)
				)
			)
			(property "Description" "SMD Chip Resistor, 220 ohm, ± 1%, 62.5 mW, 0402 [1005 Metric], Thick Film, General Purpose"
				(at 0 0 0)
				(effects
					(font
						(size 1.27 1.27)
					)
					(hide yes)
				)
			)
			(property "MPN" "CR0402-FX-2200GLF"
				(at 20.32 -20.32 0)
				(effects
					(font
						(size 1.27 1.27)
						(thickness 0.15)
					)
					(justify left bottom)
					(hide yes)
				)
			)
			(property "Manufacturer" "Bourns"
				(at 20.32 -22.86 0)
				(effects
					(font
						(size 1.27 1.27)
						(thickness 0.15)
					)
					(justify left bottom)
					(hide yes)
				)
			)
			(property "License" "Apache-2.0"
				(at 20.32 -25.4 0)
				(effects
					(font
						(size 1.27 1.27)
						(thickness 0.15)
					)
					(justify left bottom)
					(hide yes)
				)
			)
			(property "Author" "Antmicro"
				(at 20.32 -27.94 0)
				(effects
					(font
						(size 1.27 1.27)
						(thickness 0.15)
					)
					(justify left bottom)
					(hide yes)
				)
			)
			(property "Val" "220R"
				(at 20.32 -7.62 0)
				(effects
					(font
						(size 1.27 1.27)
						(thickness 0.15)
					)
					(justify left bottom)
				)
			)
			(property "Tolerance" "1%"
				(at 20.32 -10.16 0)
				(effects
					(font
						(size 1.27 1.27)
					)
					(justify left bottom)
					(hide yes)
				)
			)
			(property "ki_keywords" "0402, SMT, RESISTOR, PASSIVE"
				(at 0 0 0)
				(effects
					(font
						(size 1.27 1.27)
					)
					(hide yes)
				)
			)
			(symbol "R_220R_0402_0_1"
				(rectangle
					(start 0.635 0.889)
					(end 4.445 -0.889)
					(stroke
						(width 0.254)
						(type default)
					)
					(fill
						(type none)
					)
				)
			)
			(symbol "R_220R_0402_1_1"
				(pin passive line
					(at 0 0 0)
					(length 0.635)
					(name "~"
						(effects
							(font
								(size 1.27 1.27)
							)
						)
					)
					(number "1"
						(effects
							(font
								(size 1.27 1.27)
							)
						)
					)
				)
				(pin passive line
					(at 5.08 0 180)
					(length 0.635)
					(name "~"
						(effects
							(font
								(size 1.27 1.27)
							)
						)
					)
					(number "2"
						(effects
							(font
								(size 1.27 1.27)
							)
						)
					)
				)
			)
		)
	(symbol "antmicroResistors0402:R_22k_0402"
			(pin_numbers
				(hide yes)
			)
			(pin_names
				(hide yes)
			)
			(exclude_from_sim no)
			(in_bom yes)
			(on_board yes)
			(property "Reference" "R"
				(at 20.32 -5.08 0)
				(effects
					(font
						(size 1.27 1.27)
						(thickness 0.15)
					)
					(justify left bottom)
				)
			)
			(property "Value" "R_22k_0402"
				(at 20.32 -12.7 0)
				(effects
					(font
						(size 1.27 1.27)
						(thickness 0.15)
					)
					(justify left bottom)
					(hide yes)
				)
			)
			(property "Footprint" "antmicro-footprints:R_0402_1005Metric"
				(at 20.32 -15.24 0)
				(effects
					(font
						(size 1.27 1.27)
						(thickness 0.15)
					)
					(justify left bottom)
					(hide yes)
				)
			)
			(property "Datasheet" "https://www.bourns.com/docs/product-datasheets/cr.pdf"
				(at 20.32 -17.78 0)
				(effects
					(font
						(size 1.27 1.27)
						(thickness 0.15)
					)
					(justify left bottom)
					(hide yes)
				)
			)
			(property "Description" "SMD Chip Resistor, 22 kohm, ± 1%, 62.5 mW, 0402 [1005 Metric], Thick Film, General Purpose"
				(at 0 0 0)
				(effects
					(font
						(size 1.27 1.27)
					)
					(hide yes)
				)
			)
			(property "MPN" "CR0402-FX-2202GLF"
				(at 20.32 -20.32 0)
				(effects
					(font
						(size 1.27 1.27)
						(thickness 0.15)
					)
					(justify left bottom)
					(hide yes)
				)
			)
			(property "Manufacturer" "Bourns"
				(at 20.32 -22.86 0)
				(effects
					(font
						(size 1.27 1.27)
						(thickness 0.15)
					)
					(justify left bottom)
					(hide yes)
				)
			)
			(property "License" "Apache-2.0"
				(at 20.32 -25.4 0)
				(effects
					(font
						(size 1.27 1.27)
						(thickness 0.15)
					)
					(justify left bottom)
					(hide yes)
				)
			)
			(property "Author" "Antmicro"
				(at 20.32 -27.94 0)
				(effects
					(font
						(size 1.27 1.27)
						(thickness 0.15)
					)
					(justify left bottom)
					(hide yes)
				)
			)
			(property "Val" "22k"
				(at 20.32 -7.62 0)
				(effects
					(font
						(size 1.27 1.27)
						(thickness 0.15)
					)
					(justify left bottom)
				)
			)
			(property "Tolerance" "1%"
				(at 20.32 -10.16 0)
				(effects
					(font
						(size 1.27 1.27)
					)
					(justify left bottom)
					(hide yes)
				)
			)
			(property "ki_keywords" "0402, SMT, RESISTOR, PASSIVE"
				(at 0 0 0)
				(effects
					(font
						(size 1.27 1.27)
					)
					(hide yes)
				)
			)
			(symbol "R_22k_0402_0_1"
				(rectangle
					(start 0.635 0.889)
					(end 4.445 -0.889)
					(stroke
						(width 0.254)
						(type default)
					)
					(fill
						(type none)
					)
				)
			)
			(symbol "R_22k_0402_1_1"
				(pin passive line
					(at 0 0 0)
					(length 0.635)
					(name "~"
						(effects
							(font
								(size 1.27 1.27)
							)
						)
					)
					(number "1"
						(effects
							(font
								(size 1.27 1.27)
							)
						)
					)
				)
				(pin passive line
					(at 5.08 0 180)
					(length 0.635)
					(name "~"
						(effects
							(font
								(size 1.27 1.27)
							)
						)
					)
					(number "2"
						(effects
							(font
								(size 1.27 1.27)
							)
						)
					)
				)
			)
		)
	(symbol "antmicroResistors0402:R_2k2_0402"
			(pin_numbers
				(hide yes)
			)
			(pin_names
				(hide yes)
			)
			(exclude_from_sim no)
			(in_bom yes)
			(on_board yes)
			(property "Reference" "R"
				(at 20.32 -5.08 0)
				(effects
					(font
						(size 1.27 1.27)
						(thickness 0.15)
					)
					(justify left bottom)
				)
			)
			(property "Value" "R_2k2_0402"
				(at 20.32 -12.7 0)
				(effects
					(font
						(size 1.27 1.27)
						(thickness 0.15)
					)
					(justify left bottom)
					(hide yes)
				)
			)
			(property "Footprint" "antmicro-footprints:R_0402_1005Metric"
				(at 20.32 -15.24 0)
				(effects
					(font
						(size 1.27 1.27)
						(thickness 0.15)
					)
					(justify left bottom)
					(hide yes)
				)
			)
			(property "Datasheet" "https://www.bourns.com/docs/product-datasheets/cr.pdf"
				(at 20.32 -17.78 0)
				(effects
					(font
						(size 1.27 1.27)
						(thickness 0.15)
					)
					(justify left bottom)
					(hide yes)
				)
			)
			(property "Description" "SMD Chip Resistor, 2.2 kohm, ± 1%, 62.5 mW, 0402 [1005 Metric], Thick Film, General Purpose"
				(at 0 0 0)
				(effects
					(font
						(size 1.27 1.27)
					)
					(hide yes)
				)
			)
			(property "MPN" "CR0402-FX-2201GLF"
				(at 20.32 -20.32 0)
				(effects
					(font
						(size 1.27 1.27)
						(thickness 0.15)
					)
					(justify left bottom)
					(hide yes)
				)
			)
			(property "Manufacturer" "Bourns"
				(at 20.32 -22.86 0)
				(effects
					(font
						(size 1.27 1.27)
						(thickness 0.15)
					)
					(justify left bottom)
					(hide yes)
				)
			)
			(property "License" "Apache-2.0"
				(at 20.32 -25.4 0)
				(effects
					(font
						(size 1.27 1.27)
						(thickness 0.15)
					)
					(justify left bottom)
					(hide yes)
				)
			)
			(property "Author" "Antmicro"
				(at 20.32 -27.94 0)
				(effects
					(font
						(size 1.27 1.27)
						(thickness 0.15)
					)
					(justify left bottom)
					(hide yes)
				)
			)
			(property "Val" "2k2"
				(at 20.32 -7.62 0)
				(effects
					(font
						(size 1.27 1.27)
						(thickness 0.15)
					)
					(justify left bottom)
				)
			)
			(property "Tolerance" "1%"
				(at 20.32 -10.16 0)
				(effects
					(font
						(size 1.27 1.27)
					)
					(justify left bottom)
					(hide yes)
				)
			)
			(property "ki_keywords" "0402, SMT, RESISTOR, PASSIVE"
				(at 0 0 0)
				(effects
					(font
						(size 1.27 1.27)
					)
					(hide yes)
				)
			)
			(symbol "R_2k2_0402_0_1"
				(rectangle
					(start 0.635 0.889)
					(end 4.445 -0.889)
					(stroke
						(width 0.254)
						(type default)
					)
					(fill
						(type none)
					)
				)
			)
			(symbol "R_2k2_0402_1_1"
				(pin passive line
					(at 0 0 0)
					(length 0.635)
					(name "~"
						(effects
							(font
								(size 1.27 1.27)
							)
						)
					)
					(number "1"
						(effects
							(font
								(size 1.27 1.27)
							)
						)
					)
				)
				(pin passive line
					(at 5.08 0 180)
					(length 0.635)
					(name "~"
						(effects
							(font
								(size 1.27 1.27)
							)
						)
					)
					(number "2"
						(effects
							(font
								(size 1.27 1.27)
							)
						)
					)
				)
			)
		)
	(symbol "antmicroResistors0402:R_2k_0402"
			(pin_numbers
				(hide yes)
			)
			(pin_names
				(hide yes)
			)
			(exclude_from_sim no)
			(in_bom yes)
			(on_board yes)
			(property "Reference" "R"
				(at 20.32 -5.08 0)
				(effects
					(font
						(size 1.27 1.27)
						(thickness 0.15)
					)
					(justify left bottom)
				)
			)
			(property "Value" "R_2k_0402"
				(at 20.32 -12.7 0)
				(effects
					(font
						(size 1.27 1.27)
						(thickness 0.15)
					)
					(justify left bottom)
					(hide yes)
				)
			)
			(property "Footprint" "antmicro-footprints:R_0402_1005Metric"
				(at 20.32 -15.24 0)
				(effects
					(font
						(size 1.27 1.27)
						(thickness 0.15)
					)
					(justify left bottom)
					(hide yes)
				)
			)
			(property "Datasheet" "https://www.bourns.com/docs/product-datasheets/cr.pdf"
				(at 20.32 -17.78 0)
				(effects
					(font
						(size 1.27 1.27)
						(thickness 0.15)
					)
					(justify left bottom)
					(hide yes)
				)
			)
			(property "Description" "SMD Chip Resistor, 2 kohm, ± 1%, 62.5 mW, 0402 [1005 Metric], Thick Film, General Purpose"
				(at 0 0 0)
				(effects
					(font
						(size 1.27 1.27)
					)
					(hide yes)
				)
			)
			(property "MPN" "CR0402-FX-2001GLF"
				(at 20.32 -20.32 0)
				(effects
					(font
						(size 1.27 1.27)
						(thickness 0.15)
					)
					(justify left bottom)
					(hide yes)
				)
			)
			(property "Manufacturer" "Bourns"
				(at 20.32 -22.86 0)
				(effects
					(font
						(size 1.27 1.27)
						(thickness 0.15)
					)
					(justify left bottom)
					(hide yes)
				)
			)
			(property "License" "Apache-2.0"
				(at 20.32 -25.4 0)
				(effects
					(font
						(size 1.27 1.27)
						(thickness 0.15)
					)
					(justify left bottom)
					(hide yes)
				)
			)
			(property "Author" "Antmicro"
				(at 20.32 -27.94 0)
				(effects
					(font
						(size 1.27 1.27)
						(thickness 0.15)
					)
					(justify left bottom)
					(hide yes)
				)
			)
			(property "Val" "2k"
				(at 20.32 -7.62 0)
				(effects
					(font
						(size 1.27 1.27)
						(thickness 0.15)
					)
					(justify left bottom)
				)
			)
			(property "Tolerance" "1%"
				(at 20.32 -10.16 0)
				(effects
					(font
						(size 1.27 1.27)
					)
					(justify left bottom)
					(hide yes)
				)
			)
			(property "ki_keywords" "0402, SMT, RESISTOR, PASSIVE"
				(at 0 0 0)
				(effects
					(font
						(size 1.27 1.27)
					)
					(hide yes)
				)
			)
			(symbol "R_2k_0402_0_1"
				(rectangle
					(start 0.635 0.889)
					(end 4.445 -0.889)
					(stroke
						(width 0.254)
						(type default)
					)
					(fill
						(type none)
					)
				)
			)
			(symbol "R_2k_0402_1_1"
				(pin passive line
					(at 0 0 0)
					(length 0.635)
					(name "~"
						(effects
							(font
								(size 1.27 1.27)
							)
						)
					)
					(number "1"
						(effects
							(font
								(size 1.27 1.27)
							)
						)
					)
				)
				(pin passive line
					(at 5.08 0 180)
					(length 0.635)
					(name "~"
						(effects
							(font
								(size 1.27 1.27)
							)
						)
					)
					(number "2"
						(effects
							(font
								(size 1.27 1.27)
							)
						)
					)
				)
			)
		)
	(symbol "antmicroResistors0402:R_316k_0402"
			(pin_numbers
				(hide yes)
			)
			(pin_names
				(hide yes)
			)
			(exclude_from_sim no)
			(in_bom yes)
			(on_board yes)
			(property "Reference" "R"
				(at 20.32 -5.08 0)
				(effects
					(font
						(size 1.27 1.27)
						(thickness 0.15)
					)
					(justify left bottom)
				)
			)
			(property "Value" "R_316k_0402"
				(at 20.32 -12.7 0)
				(effects
					(font
						(size 1.27 1.27)
						(thickness 0.15)
					)
					(justify left bottom)
					(hide yes)
				)
			)
			(property "Footprint" "antmicro-footprints:R_0402_1005Metric"
				(at 20.32 -15.24 0)
				(effects
					(font
						(size 1.27 1.27)
						(thickness 0.15)
					)
					(justify left bottom)
					(hide yes)
				)
			)
			(property "Datasheet" "https://www.bourns.com/docs/product-datasheets/cr.pdf"
				(at 20.32 -17.78 0)
				(effects
					(font
						(size 1.27 1.27)
						(thickness 0.15)
					)
					(justify left bottom)
					(hide yes)
				)
			)
			(property "Description" "SMD Chip Resistor"
				(at 0 0 0)
				(effects
					(font
						(size 1.27 1.27)
					)
					(hide yes)
				)
			)
			(property "MPN" "CR0402-FX-3163GLF"
				(at 20.32 -20.32 0)
				(effects
					(font
						(size 1.27 1.27)
						(thickness 0.15)
					)
					(justify left bottom)
					(hide yes)
				)
			)
			(property "Manufacturer" "Bourns"
				(at 20.32 -22.86 0)
				(effects
					(font
						(size 1.27 1.27)
						(thickness 0.15)
					)
					(justify left bottom)
					(hide yes)
				)
			)
			(property "License" "Apache-2.0"
				(at 20.32 -25.4 0)
				(effects
					(font
						(size 1.27 1.27)
						(thickness 0.15)
					)
					(justify left bottom)
					(hide yes)
				)
			)
			(property "Author" "Antmicro"
				(at 20.32 -27.94 0)
				(effects
					(font
						(size 1.27 1.27)
						(thickness 0.15)
					)
					(justify left bottom)
					(hide yes)
				)
			)
			(property "Val" "316k"
				(at 20.32 -7.62 0)
				(effects
					(font
						(size 1.27 1.27)
						(thickness 0.15)
					)
					(justify left bottom)
				)
			)
			(property "Tolerance" "1%"
				(at 20.32 -10.16 0)
				(effects
					(font
						(size 1.27 1.27)
					)
					(justify left bottom)
					(hide yes)
				)
			)
			(property "ki_keywords" "0402, SMT, RESISTOR, PASSIVE"
				(at 0 0 0)
				(effects
					(font
						(size 1.27 1.27)
					)
					(hide yes)
				)
			)
			(symbol "R_316k_0402_0_1"
				(rectangle
					(start 0.635 0.889)
					(end 4.445 -0.889)
					(stroke
						(width 0.254)
						(type default)
					)
					(fill
						(type none)
					)
				)
			)
			(symbol "R_316k_0402_1_1"
				(pin passive line
					(at 0 0 0)
					(length 0.635)
					(name "~"
						(effects
							(font
								(size 1.27 1.27)
							)
						)
					)
					(number "1"
						(effects
							(font
								(size 1.27 1.27)
							)
						)
					)
				)
				(pin passive line
					(at 5.08 0 180)
					(length 0.635)
					(name "~"
						(effects
							(font
								(size 1.27 1.27)
							)
						)
					)
					(number "2"
						(effects
							(font
								(size 1.27 1.27)
							)
						)
					)
				)
			)
		)
	(symbol "antmicroResistors0402:R_3R3_0402"
			(pin_numbers
				(hide yes)
			)
			(pin_names
				(hide yes)
			)
			(exclude_from_sim no)
			(in_bom yes)
			(on_board yes)
			(property "Reference" "R"
				(at 20.32 -5.08 0)
				(effects
					(font
						(size 1.27 1.27)
						(thickness 0.15)
					)
					(justify left bottom)
				)
			)
			(property "Value" "R_3R3_0402"
				(at 20.32 -12.7 0)
				(effects
					(font
						(size 1.27 1.27)
						(thickness 0.15)
					)
					(justify left bottom)
					(hide yes)
				)
			)
			(property "Footprint" "antmicro-footprints:R_0402_1005Metric"
				(at 20.32 -15.24 0)
				(effects
					(font
						(size 1.27 1.27)
						(thickness 0.15)
					)
					(justify left bottom)
					(hide yes)
				)
			)
			(property "Datasheet" "https://www.bourns.com/docs/product-datasheets/cr.pdf"
				(at 20.32 -17.78 0)
				(effects
					(font
						(size 1.27 1.27)
						(thickness 0.15)
					)
					(justify left bottom)
					(hide yes)
				)
			)
			(property "Description" "SMD Chip Resistor, 3.3 ohm, ± 1%, 62.5 mW, 0402 [1005 Metric], Thick Film, General Purpose"
				(at 0 0 0)
				(effects
					(font
						(size 1.27 1.27)
					)
					(hide yes)
				)
			)
			(property "MPN" "CR0402-FX-3R30GLF"
				(at 20.32 -20.32 0)
				(effects
					(font
						(size 1.27 1.27)
						(thickness 0.15)
					)
					(justify left bottom)
					(hide yes)
				)
			)
			(property "Manufacturer" "Bourns"
				(at 20.32 -22.86 0)
				(effects
					(font
						(size 1.27 1.27)
						(thickness 0.15)
					)
					(justify left bottom)
					(hide yes)
				)
			)
			(property "License" "Apache-2.0"
				(at 20.32 -25.4 0)
				(effects
					(font
						(size 1.27 1.27)
						(thickness 0.15)
					)
					(justify left bottom)
					(hide yes)
				)
			)
			(property "Author" "Antmicro"
				(at 20.32 -27.94 0)
				(effects
					(font
						(size 1.27 1.27)
						(thickness 0.15)
					)
					(justify left bottom)
					(hide yes)
				)
			)
			(property "Val" "3R3"
				(at 20.32 -7.62 0)
				(effects
					(font
						(size 1.27 1.27)
						(thickness 0.15)
					)
					(justify left bottom)
				)
			)
			(property "Tolerance" "1%"
				(at 20.32 -10.16 0)
				(effects
					(font
						(size 1.27 1.27)
					)
					(justify left bottom)
					(hide yes)
				)
			)
			(property "ki_keywords" "0402, SMT, RESISTOR, PASSIVE"
				(at 0 0 0)
				(effects
					(font
						(size 1.27 1.27)
					)
					(hide yes)
				)
			)
			(symbol "R_3R3_0402_0_1"
				(rectangle
					(start 0.635 0.889)
					(end 4.445 -0.889)
					(stroke
						(width 0.254)
						(type default)
					)
					(fill
						(type none)
					)
				)
			)
			(symbol "R_3R3_0402_1_1"
				(pin passive line
					(at 0 0 0)
					(length 0.635)
					(name "~"
						(effects
							(font
								(size 1.27 1.27)
							)
						)
					)
					(number "1"
						(effects
							(font
								(size 1.27 1.27)
							)
						)
					)
				)
				(pin passive line
					(at 5.08 0 180)
					(length 0.635)
					(name "~"
						(effects
							(font
								(size 1.27 1.27)
							)
						)
					)
					(number "2"
						(effects
							(font
								(size 1.27 1.27)
							)
						)
					)
				)
			)
		)
	(symbol "antmicroResistors0402:R_3k16_0402"
			(pin_numbers
				(hide yes)
			)
			(pin_names
				(hide yes)
			)
			(exclude_from_sim no)
			(in_bom yes)
			(on_board yes)
			(property "Reference" "R"
				(at 15.24 -5.08 0)
				(effects
					(font
						(size 1.27 1.27)
						(thickness 0.15)
					)
					(justify left bottom)
				)
			)
			(property "Value" "R_3k16_0402"
				(at 15.24 -10.16 0)
				(effects
					(font
						(size 1.27 1.27)
						(thickness 0.15)
					)
					(justify left bottom)
					(hide yes)
				)
			)
			(property "Footprint" "antmicro-footprints:R_0402_1005Metric"
				(at 15.24 -12.7 0)
				(effects
					(font
						(size 1.27 1.27)
						(thickness 0.15)
					)
					(justify left bottom)
					(hide yes)
				)
			)
			(property "Datasheet" "https://www.mouser.com/datasheet/2/447/YAGEO_PYu_RC_Group_51_RoHS_L_12-3313492.pdf"
				(at 15.24 -15.24 0)
				(effects
					(font
						(size 1.27 1.27)
						(thickness 0.15)
					)
					(justify left bottom)
					(hide yes)
				)
			)
			(property "Description" "SMD Chip Resistor, 3.16 kohm, ± 1%, 62.5 mW, 0402 [1005 Metric], Thick Film, General Purpose"
				(at 0 0 0)
				(effects
					(font
						(size 1.27 1.27)
					)
					(hide yes)
				)
			)
			(property "MPN" "RC0402FR-073K16L"
				(at 15.24 -17.78 0)
				(effects
					(font
						(size 1.27 1.27)
						(thickness 0.15)
					)
					(justify left bottom)
					(hide yes)
				)
			)
			(property "Val" "3k16"
				(at 15.24 -7.62 0)
				(effects
					(font
						(size 1.27 1.27)
						(thickness 0.15)
					)
					(justify left bottom)
				)
			)
			(property "Manufacturer" "YAGEO"
				(at 15.24 -20.32 0)
				(effects
					(font
						(size 1.27 1.27)
						(thickness 0.15)
					)
					(justify left bottom)
					(hide yes)
				)
			)
			(property "Tolerance" "1%"
				(at 15.24 -22.86 0)
				(effects
					(font
						(size 1.27 1.27)
						(thickness 0.15)
					)
					(justify left bottom)
					(hide yes)
				)
			)
			(property "Author" "Antmicro"
				(at 15.24 -25.4 0)
				(effects
					(font
						(size 1.27 1.27)
						(thickness 0.15)
					)
					(justify left bottom)
					(hide yes)
				)
			)
			(property "License" "Apache-2.0"
				(at 15.24 -27.94 0)
				(effects
					(font
						(size 1.27 1.27)
						(thickness 0.15)
					)
					(justify left bottom)
					(hide yes)
				)
			)
			(property "ki_keywords" "0402, SMT, RESISTOR, PASSIVE"
				(at 0 0 0)
				(effects
					(font
						(size 1.27 1.27)
					)
					(hide yes)
				)
			)
			(symbol "R_3k16_0402_0_1"
				(rectangle
					(start 0.635 0.889)
					(end 4.445 -0.889)
					(stroke
						(width 0.254)
						(type default)
					)
					(fill
						(type none)
					)
				)
			)
			(symbol "R_3k16_0402_1_1"
				(pin passive line
					(at 0 0 0)
					(length 0.635)
					(name "~"
						(effects
							(font
								(size 1.27 1.27)
							)
						)
					)
					(number "1"
						(effects
							(font
								(size 1.27 1.27)
							)
						)
					)
				)
				(pin passive line
					(at 5.08 0 180)
					(length 0.635)
					(name "~"
						(effects
							(font
								(size 1.27 1.27)
							)
						)
					)
					(number "2"
						(effects
							(font
								(size 1.27 1.27)
							)
						)
					)
				)
			)
		)
	(symbol "antmicroResistors0402:R_470R_0402"
			(pin_numbers
				(hide yes)
			)
			(pin_names
				(hide yes)
			)
			(exclude_from_sim no)
			(in_bom yes)
			(on_board yes)
			(property "Reference" "R"
				(at 20.32 -5.08 0)
				(effects
					(font
						(size 1.27 1.27)
						(thickness 0.15)
					)
					(justify left bottom)
				)
			)
			(property "Value" "R_470R_0402"
				(at 20.32 -12.7 0)
				(effects
					(font
						(size 1.27 1.27)
						(thickness 0.15)
					)
					(justify left bottom)
					(hide yes)
				)
			)
			(property "Footprint" "antmicro-footprints:R_0402_1005Metric"
				(at 20.32 -15.24 0)
				(effects
					(font
						(size 1.27 1.27)
						(thickness 0.15)
					)
					(justify left bottom)
					(hide yes)
				)
			)
			(property "Datasheet" "https://www.bourns.com/docs/product-datasheets/cr.pdf"
				(at 20.32 -17.78 0)
				(effects
					(font
						(size 1.27 1.27)
						(thickness 0.15)
					)
					(justify left bottom)
					(hide yes)
				)
			)
			(property "Description" "SMD Chip Resistor, 470 ohm, ± 1%, 62.5 mW, 0402 [1005 Metric], Thick Film, General Purpose"
				(at 0 0 0)
				(effects
					(font
						(size 1.27 1.27)
					)
					(hide yes)
				)
			)
			(property "MPN" "CR0402-FX-4700GLF"
				(at 20.32 -20.32 0)
				(effects
					(font
						(size 1.27 1.27)
						(thickness 0.15)
					)
					(justify left bottom)
					(hide yes)
				)
			)
			(property "Manufacturer" "Bourns"
				(at 20.32 -22.86 0)
				(effects
					(font
						(size 1.27 1.27)
						(thickness 0.15)
					)
					(justify left bottom)
					(hide yes)
				)
			)
			(property "License" "Apache-2.0"
				(at 20.32 -25.4 0)
				(effects
					(font
						(size 1.27 1.27)
						(thickness 0.15)
					)
					(justify left bottom)
					(hide yes)
				)
			)
			(property "Author" "Antmicro"
				(at 20.32 -27.94 0)
				(effects
					(font
						(size 1.27 1.27)
						(thickness 0.15)
					)
					(justify left bottom)
					(hide yes)
				)
			)
			(property "Val" "470R"
				(at 20.32 -7.62 0)
				(effects
					(font
						(size 1.27 1.27)
						(thickness 0.15)
					)
					(justify left bottom)
				)
			)
			(property "Tolerance" "1%"
				(at 20.32 -10.16 0)
				(effects
					(font
						(size 1.27 1.27)
					)
					(justify left bottom)
					(hide yes)
				)
			)
			(property "ki_keywords" "0402, SMT, RESISTOR, PASSIVE"
				(at 0 0 0)
				(effects
					(font
						(size 1.27 1.27)
					)
					(hide yes)
				)
			)
			(symbol "R_470R_0402_0_1"
				(rectangle
					(start 0.635 0.889)
					(end 4.445 -0.889)
					(stroke
						(width 0.254)
						(type default)
					)
					(fill
						(type none)
					)
				)
			)
			(symbol "R_470R_0402_1_1"
				(pin passive line
					(at 0 0 0)
					(length 0.635)
					(name "~"
						(effects
							(font
								(size 1.27 1.27)
							)
						)
					)
					(number "1"
						(effects
							(font
								(size 1.27 1.27)
							)
						)
					)
				)
				(pin passive line
					(at 5.08 0 180)
					(length 0.635)
					(name "~"
						(effects
							(font
								(size 1.27 1.27)
							)
						)
					)
					(number "2"
						(effects
							(font
								(size 1.27 1.27)
							)
						)
					)
				)
			)
		)
	(symbol "antmicroResistors0402:R_4k7_0402"
			(pin_numbers
				(hide yes)
			)
			(pin_names
				(hide yes)
			)
			(exclude_from_sim no)
			(in_bom yes)
			(on_board yes)
			(property "Reference" "R"
				(at 20.32 -5.08 0)
				(effects
					(font
						(size 1.27 1.27)
						(thickness 0.15)
					)
					(justify left bottom)
				)
			)
			(property "Value" "R_4k7_0402"
				(at 20.32 -12.7 0)
				(effects
					(font
						(size 1.27 1.27)
						(thickness 0.15)
					)
					(justify left bottom)
					(hide yes)
				)
			)
			(property "Footprint" "antmicro-footprints:R_0402_1005Metric"
				(at 20.32 -15.24 0)
				(effects
					(font
						(size 1.27 1.27)
						(thickness 0.15)
					)
					(justify left bottom)
					(hide yes)
				)
			)
			(property "Datasheet" "https://www.bourns.com/docs/product-datasheets/cr.pdf"
				(at 20.32 -17.78 0)
				(effects
					(font
						(size 1.27 1.27)
						(thickness 0.15)
					)
					(justify left bottom)
					(hide yes)
				)
			)
			(property "Description" "SMD Chip Resistor, 4.7 kohm, ± 1%, 62.5 mW, 0402 [1005 Metric], Thick Film, General Purpose"
				(at 0 0 0)
				(effects
					(font
						(size 1.27 1.27)
					)
					(hide yes)
				)
			)
			(property "MPN" "CR0402-FX-4701GLF"
				(at 20.32 -20.32 0)
				(effects
					(font
						(size 1.27 1.27)
						(thickness 0.15)
					)
					(justify left bottom)
					(hide yes)
				)
			)
			(property "Manufacturer" "Bourns"
				(at 20.32 -22.86 0)
				(effects
					(font
						(size 1.27 1.27)
						(thickness 0.15)
					)
					(justify left bottom)
					(hide yes)
				)
			)
			(property "License" "Apache-2.0"
				(at 20.32 -25.4 0)
				(effects
					(font
						(size 1.27 1.27)
						(thickness 0.15)
					)
					(justify left bottom)
					(hide yes)
				)
			)
			(property "Author" "Antmicro"
				(at 20.32 -27.94 0)
				(effects
					(font
						(size 1.27 1.27)
						(thickness 0.15)
					)
					(justify left bottom)
					(hide yes)
				)
			)
			(property "Val" "4k7"
				(at 20.32 -7.62 0)
				(effects
					(font
						(size 1.27 1.27)
						(thickness 0.15)
					)
					(justify left bottom)
				)
			)
			(property "Tolerance" "1%"
				(at 20.32 -10.16 0)
				(effects
					(font
						(size 1.27 1.27)
					)
					(justify left bottom)
					(hide yes)
				)
			)
			(property "ki_keywords" "0402, SMT, RESISTOR, PASSIVE"
				(at 0 0 0)
				(effects
					(font
						(size 1.27 1.27)
					)
					(hide yes)
				)
			)
			(symbol "R_4k7_0402_0_1"
				(rectangle
					(start 0.635 0.889)
					(end 4.445 -0.889)
					(stroke
						(width 0.254)
						(type default)
					)
					(fill
						(type none)
					)
				)
			)
			(symbol "R_4k7_0402_1_1"
				(pin passive line
					(at 0 0 0)
					(length 0.635)
					(name "~"
						(effects
							(font
								(size 1.27 1.27)
							)
						)
					)
					(number "1"
						(effects
							(font
								(size 1.27 1.27)
							)
						)
					)
				)
				(pin passive line
					(at 5.08 0 180)
					(length 0.635)
					(name "~"
						(effects
							(font
								(size 1.27 1.27)
							)
						)
					)
					(number "2"
						(effects
							(font
								(size 1.27 1.27)
							)
						)
					)
				)
			)
		)
	(symbol "antmicroResistors0402:R_5k23_0402"
			(pin_numbers
				(hide yes)
			)
			(pin_names
				(hide yes)
			)
			(exclude_from_sim no)
			(in_bom yes)
			(on_board yes)
			(property "Reference" "R"
				(at 20.32 -5.08 0)
				(effects
					(font
						(size 1.27 1.27)
						(thickness 0.15)
					)
					(justify left bottom)
				)
			)
			(property "Value" "R_5k23_0402"
				(at 20.32 -12.7 0)
				(effects
					(font
						(size 1.27 1.27)
						(thickness 0.15)
					)
					(justify left bottom)
					(hide yes)
				)
			)
			(property "Footprint" "antmicro-footprints:R_0402_1005Metric"
				(at 20.32 -15.24 0)
				(effects
					(font
						(size 1.27 1.27)
						(thickness 0.15)
					)
					(justify left bottom)
					(hide yes)
				)
			)
			(property "Datasheet" "https://www.farnell.com/datasheets/3795017.pdf"
				(at 20.32 -17.78 0)
				(effects
					(font
						(size 1.27 1.27)
						(thickness 0.15)
					)
					(justify left bottom)
					(hide yes)
				)
			)
			(property "Description" "SMD Chip Resistor, 5.23 kohm, ± 1%, 63 mW, 0402 [1005 Metric], Thick Film, General Purpose"
				(at 0 0 0)
				(effects
					(font
						(size 1.27 1.27)
					)
					(hide yes)
				)
			)
			(property "MPN" "RC0402FR-075K23L"
				(at 20.32 -20.32 0)
				(effects
					(font
						(size 1.27 1.27)
						(thickness 0.15)
					)
					(justify left bottom)
					(hide yes)
				)
			)
			(property "Manufacturer" "YAGEO"
				(at 20.32 -22.86 0)
				(effects
					(font
						(size 1.27 1.27)
						(thickness 0.15)
					)
					(justify left bottom)
					(hide yes)
				)
			)
			(property "License" "Apache-2.0"
				(at 20.32 -25.4 0)
				(effects
					(font
						(size 1.27 1.27)
						(thickness 0.15)
					)
					(justify left bottom)
					(hide yes)
				)
			)
			(property "Author" "Antmicro"
				(at 20.32 -27.94 0)
				(effects
					(font
						(size 1.27 1.27)
						(thickness 0.15)
					)
					(justify left bottom)
					(hide yes)
				)
			)
			(property "Val" "5k23"
				(at 20.32 -7.62 0)
				(effects
					(font
						(size 1.27 1.27)
						(thickness 0.15)
					)
					(justify left bottom)
				)
			)
			(property "Tolerance" "1%"
				(at 20.32 -10.16 0)
				(effects
					(font
						(size 1.27 1.27)
					)
					(justify left bottom)
					(hide yes)
				)
			)
			(property "ki_keywords" "0402, SMT, RESISTOR, PASSIVE"
				(at 0 0 0)
				(effects
					(font
						(size 1.27 1.27)
					)
					(hide yes)
				)
			)
			(symbol "R_5k23_0402_0_1"
				(rectangle
					(start 0.635 0.889)
					(end 4.445 -0.889)
					(stroke
						(width 0.254)
						(type default)
					)
					(fill
						(type none)
					)
				)
			)
			(symbol "R_5k23_0402_1_1"
				(pin passive line
					(at 0 0 0)
					(length 0.635)
					(name "~"
						(effects
							(font
								(size 1.27 1.27)
							)
						)
					)
					(number "1"
						(effects
							(font
								(size 1.27 1.27)
							)
						)
					)
				)
				(pin passive line
					(at 5.08 0 180)
					(length 0.635)
					(name "~"
						(effects
							(font
								(size 1.27 1.27)
							)
						)
					)
					(number "2"
						(effects
							(font
								(size 1.27 1.27)
							)
						)
					)
				)
			)
		)
	(symbol "antmicroResistors0402:R_68k_0402"
			(pin_numbers
				(hide yes)
			)
			(pin_names
				(hide yes)
			)
			(exclude_from_sim no)
			(in_bom yes)
			(on_board yes)
			(property "Reference" "R"
				(at 20.32 -5.08 0)
				(effects
					(font
						(size 1.27 1.27)
						(thickness 0.15)
					)
					(justify left bottom)
				)
			)
			(property "Value" "R_68k_0402"
				(at 20.32 -12.7 0)
				(effects
					(font
						(size 1.27 1.27)
						(thickness 0.15)
					)
					(justify left bottom)
					(hide yes)
				)
			)
			(property "Footprint" "antmicro-footprints:R_0402_1005Metric"
				(at 20.32 -15.24 0)
				(effects
					(font
						(size 1.27 1.27)
						(thickness 0.15)
					)
					(justify left bottom)
					(hide yes)
				)
			)
			(property "Datasheet" "https://www.bourns.com/docs/product-datasheets/cr.pdf"
				(at 20.32 -17.78 0)
				(effects
					(font
						(size 1.27 1.27)
						(thickness 0.15)
					)
					(justify left bottom)
					(hide yes)
				)
			)
			(property "Description" "SMD Chip Resistor"
				(at 0 0 0)
				(effects
					(font
						(size 1.27 1.27)
					)
					(hide yes)
				)
			)
			(property "MPN" "CR0402-FX-6802GLF"
				(at 20.32 -20.32 0)
				(effects
					(font
						(size 1.27 1.27)
						(thickness 0.15)
					)
					(justify left bottom)
					(hide yes)
				)
			)
			(property "Manufacturer" "Bourns"
				(at 20.32 -22.86 0)
				(effects
					(font
						(size 1.27 1.27)
						(thickness 0.15)
					)
					(justify left bottom)
					(hide yes)
				)
			)
			(property "License" "Apache-2.0"
				(at 20.32 -25.4 0)
				(effects
					(font
						(size 1.27 1.27)
						(thickness 0.15)
					)
					(justify left bottom)
					(hide yes)
				)
			)
			(property "Author" "Antmicro"
				(at 20.32 -27.94 0)
				(effects
					(font
						(size 1.27 1.27)
						(thickness 0.15)
					)
					(justify left bottom)
					(hide yes)
				)
			)
			(property "Val" "68k"
				(at 20.32 -7.62 0)
				(effects
					(font
						(size 1.27 1.27)
						(thickness 0.15)
					)
					(justify left bottom)
				)
			)
			(property "Tolerance" "1%"
				(at 20.32 -10.16 0)
				(effects
					(font
						(size 1.27 1.27)
					)
					(justify left bottom)
					(hide yes)
				)
			)
			(property "ki_keywords" "0402, SMT, RESISTOR, PASSIVE"
				(at 0 0 0)
				(effects
					(font
						(size 1.27 1.27)
					)
					(hide yes)
				)
			)
			(symbol "R_68k_0402_0_1"
				(rectangle
					(start 0.635 0.889)
					(end 4.445 -0.889)
					(stroke
						(width 0.254)
						(type default)
					)
					(fill
						(type none)
					)
				)
			)
			(symbol "R_68k_0402_1_1"
				(pin passive line
					(at 0 0 0)
					(length 0.635)
					(name "~"
						(effects
							(font
								(size 1.27 1.27)
							)
						)
					)
					(number "1"
						(effects
							(font
								(size 1.27 1.27)
							)
						)
					)
				)
				(pin passive line
					(at 5.08 0 180)
					(length 0.635)
					(name "~"
						(effects
							(font
								(size 1.27 1.27)
							)
						)
					)
					(number "2"
						(effects
							(font
								(size 1.27 1.27)
							)
						)
					)
				)
			)
		)
	(symbol "antmicroResistors0402:R_8k66_0402"
			(pin_numbers
				(hide yes)
			)
			(pin_names
				(hide yes)
			)
			(exclude_from_sim no)
			(in_bom yes)
			(on_board yes)
			(property "Reference" "R"
				(at 20.32 -5.08 0)
				(effects
					(font
						(size 1.27 1.27)
						(thickness 0.15)
					)
					(justify left bottom)
				)
			)
			(property "Value" "R_8k66_0402"
				(at 20.32 -12.7 0)
				(effects
					(font
						(size 1.27 1.27)
						(thickness 0.15)
					)
					(justify left bottom)
					(hide yes)
				)
			)
			(property "Footprint" "antmicro-footprints:R_0402_1005Metric"
				(at 20.32 -15.24 0)
				(effects
					(font
						(size 1.27 1.27)
						(thickness 0.15)
					)
					(justify left bottom)
					(hide yes)
				)
			)
			(property "Datasheet" "https://www.bourns.com/docs/product-datasheets/cr.pdf"
				(at 20.32 -17.78 0)
				(effects
					(font
						(size 1.27 1.27)
						(thickness 0.15)
					)
					(justify left bottom)
					(hide yes)
				)
			)
			(property "Description" "SMD Chip Resistor"
				(at 0 0 0)
				(effects
					(font
						(size 1.27 1.27)
					)
					(hide yes)
				)
			)
			(property "MPN" "CR0402-FX-8661GLF"
				(at 20.32 -20.32 0)
				(effects
					(font
						(size 1.27 1.27)
						(thickness 0.15)
					)
					(justify left bottom)
					(hide yes)
				)
			)
			(property "Manufacturer" "Bourns"
				(at 20.32 -22.86 0)
				(effects
					(font
						(size 1.27 1.27)
						(thickness 0.15)
					)
					(justify left bottom)
					(hide yes)
				)
			)
			(property "License" "Apache-2.0"
				(at 20.32 -25.4 0)
				(effects
					(font
						(size 1.27 1.27)
						(thickness 0.15)
					)
					(justify left bottom)
					(hide yes)
				)
			)
			(property "Author" "Antmicro"
				(at 20.32 -27.94 0)
				(effects
					(font
						(size 1.27 1.27)
						(thickness 0.15)
					)
					(justify left bottom)
					(hide yes)
				)
			)
			(property "Val" "8k66"
				(at 20.32 -7.62 0)
				(effects
					(font
						(size 1.27 1.27)
						(thickness 0.15)
					)
					(justify left bottom)
				)
			)
			(property "Tolerance" "1%"
				(at 20.32 -10.16 0)
				(effects
					(font
						(size 1.27 1.27)
					)
					(justify left bottom)
					(hide yes)
				)
			)
			(property "ki_keywords" "0402, SMT, RESISTOR, PASSIVE"
				(at 0 0 0)
				(effects
					(font
						(size 1.27 1.27)
					)
					(hide yes)
				)
			)
			(symbol "R_8k66_0402_0_1"
				(rectangle
					(start 0.635 0.889)
					(end 4.445 -0.889)
					(stroke
						(width 0.254)
						(type default)
					)
					(fill
						(type none)
					)
				)
			)
			(symbol "R_8k66_0402_1_1"
				(pin passive line
					(at 0 0 0)
					(length 0.635)
					(name "~"
						(effects
							(font
								(size 1.27 1.27)
							)
						)
					)
					(number "1"
						(effects
							(font
								(size 1.27 1.27)
							)
						)
					)
				)
				(pin passive line
					(at 5.08 0 180)
					(length 0.635)
					(name "~"
						(effects
							(font
								(size 1.27 1.27)
							)
						)
					)
					(number "2"
						(effects
							(font
								(size 1.27 1.27)
							)
						)
					)
				)
			)
		)
	(symbol "antmicroResistors0603:R_4k7_0603"
			(pin_numbers
				(hide yes)
			)
			(pin_names
				(hide yes)
			)
			(exclude_from_sim no)
			(in_bom yes)
			(on_board yes)
			(property "Reference" "R"
				(at 20.32 -5.08 0)
				(effects
					(font
						(size 1.27 1.27)
						(thickness 0.15)
					)
					(justify left bottom)
				)
			)
			(property "Value" "R_4k7_0603"
				(at 20.32 -12.7 0)
				(effects
					(font
						(size 1.27 1.27)
						(thickness 0.15)
					)
					(justify left bottom)
					(hide yes)
				)
			)
			(property "Footprint" "antmicro-footprints:R_0603_1608Metric"
				(at 20.32 -15.24 0)
				(effects
					(font
						(size 1.27 1.27)
						(thickness 0.15)
					)
					(justify left bottom)
					(hide yes)
				)
			)
			(property "Datasheet" "https://www.bourns.com/docs/product-datasheets/cr.pdf"
				(at 20.32 -17.78 0)
				(effects
					(font
						(size 1.27 1.27)
						(thickness 0.15)
					)
					(justify left bottom)
					(hide yes)
				)
			)
			(property "Description" "SMD Chip Resistor, 4.7 kohm, ± 1%, 100 mW, 0603 [1608 Metric], Thick Film, General Purpose"
				(at 0 0 0)
				(effects
					(font
						(size 1.27 1.27)
					)
					(hide yes)
				)
			)
			(property "MPN" "CR0603-FX-4701ELF"
				(at 20.32 -20.32 0)
				(effects
					(font
						(size 1.27 1.27)
						(thickness 0.15)
					)
					(justify left bottom)
					(hide yes)
				)
			)
			(property "Manufacturer" "Bourns"
				(at 20.32 -22.86 0)
				(effects
					(font
						(size 1.27 1.27)
						(thickness 0.15)
					)
					(justify left bottom)
					(hide yes)
				)
			)
			(property "License" "Apache-2.0"
				(at 20.32 -25.4 0)
				(effects
					(font
						(size 1.27 1.27)
						(thickness 0.15)
					)
					(justify left bottom)
					(hide yes)
				)
			)
			(property "Author" "Antmicro"
				(at 20.32 -27.94 0)
				(effects
					(font
						(size 1.27 1.27)
						(thickness 0.15)
					)
					(justify left bottom)
					(hide yes)
				)
			)
			(property "Val" "4k7"
				(at 20.32 -7.62 0)
				(effects
					(font
						(size 1.27 1.27)
						(thickness 0.15)
					)
					(justify left bottom)
				)
			)
			(property "Tolerance" "1%"
				(at 20.32 -10.16 0)
				(effects
					(font
						(size 1.27 1.27)
					)
					(justify left bottom)
					(hide yes)
				)
			)
			(property "ki_keywords" "0603, SMT, RESISTOR, PASSIVE"
				(at 0 0 0)
				(effects
					(font
						(size 1.27 1.27)
					)
					(hide yes)
				)
			)
			(symbol "R_4k7_0603_0_1"
				(rectangle
					(start 0.635 0.889)
					(end 4.445 -0.889)
					(stroke
						(width 0.254)
						(type default)
					)
					(fill
						(type none)
					)
				)
			)
			(symbol "R_4k7_0603_1_1"
				(pin passive line
					(at 0 0 0)
					(length 0.635)
					(name "~"
						(effects
							(font
								(size 1.27 1.27)
							)
						)
					)
					(number "1"
						(effects
							(font
								(size 1.27 1.27)
							)
						)
					)
				)
				(pin passive line
					(at 5.08 0 180)
					(length 0.635)
					(name "~"
						(effects
							(font
								(size 1.27 1.27)
							)
						)
					)
					(number "2"
						(effects
							(font
								(size 1.27 1.27)
							)
						)
					)
				)
			)
		)
	(symbol "antmicroTVSDiodes:AXGD10402KR"
			(pin_numbers
				(hide yes)
			)
			(pin_names
				(hide yes)
			)
			(exclude_from_sim no)
			(in_bom yes)
			(on_board yes)
			(property "Reference" "D"
				(at 25.4 -5.08 0)
				(effects
					(font
						(size 1.27 1.27)
						(thickness 0.15)
					)
					(justify left bottom)
				)
			)
			(property "Value" "AXGD10402KR"
				(at 25.4 -10.16 0)
				(effects
					(font
						(size 1.27 1.27)
						(thickness 0.15)
					)
					(justify left bottom)
					(hide yes)
				)
			)
			(property "Footprint" "antmicro-footprints:D_0402_1005Metric"
				(at 25.4 -12.7 0)
				(effects
					(font
						(size 1.27 1.27)
						(thickness 0.15)
					)
					(justify left bottom)
					(hide yes)
				)
			)
			(property "Datasheet" "https://www.littelfuse.com/media?resourcetype=datasheets&itemid=020b2bf2-064c-4ff1-a898-b4ec805b2fea&filename=littelfuse-xtremeguard-axgd-datasheet"
				(at 25.4 -15.24 0)
				(effects
					(font
						(size 1.27 1.27)
						(thickness 0.15)
					)
					(justify left bottom)
					(hide yes)
				)
			)
			(property "Description" "Bidirectional TVS, 30 kV,  0402, 24 V, 0.04 pF"
				(at 0 0 0)
				(effects
					(font
						(size 1.27 1.27)
					)
					(hide yes)
				)
			)
			(property "Manufacturer" "Littelfuse"
				(at 25.4 -17.78 0)
				(effects
					(font
						(size 1.27 1.27)
						(thickness 0.15)
					)
					(justify left bottom)
					(hide yes)
				)
			)
			(property "MPN" "AXGD10402KR"
				(at 25.4 -7.62 0)
				(effects
					(font
						(size 1.27 1.27)
						(thickness 0.15)
					)
					(justify left bottom)
				)
			)
			(property "Author" "Antmicro"
				(at 25.4 -20.32 0)
				(effects
					(font
						(size 1.27 1.27)
						(thickness 0.15)
					)
					(justify left bottom)
					(hide yes)
				)
			)
			(property "License" "Apache-2.0"
				(at 25.4 -22.86 0)
				(effects
					(font
						(size 1.27 1.27)
						(thickness 0.15)
					)
					(justify left bottom)
					(hide yes)
				)
			)
			(property "ki_keywords" "DIODE, SEMICONDUCTOR, TVS, ESD"
				(at 0 0 0)
				(effects
					(font
						(size 1.27 1.27)
					)
					(hide yes)
				)
			)
			(symbol "AXGD10402KR_0_0"
				(text ""
					(at 7.62 -1.27 0)
					(effects
						(font
							(size 1.27 1.27)
						)
					)
				)
			)
			(symbol "AXGD10402KR_0_1"
				(polyline
					(pts
						(xy 0.635 0) (xy 4.445 0)
					)
					(stroke
						(width 0)
						(type default)
					)
					(fill
						(type none)
					)
				)
			)
			(symbol "AXGD10402KR_1_1"
				(polyline
					(pts
						(xy 1.016 -1.016) (xy 1.016 1.016) (xy 2.54 0) (xy 1.016 -1.016)
					)
					(stroke
						(width 0.254)
						(type default)
					)
					(fill
						(type outline)
					)
				)
				(polyline
					(pts
						(xy 2.54 1.016) (xy 2.159 1.016)
					)
					(stroke
						(width 0.254)
						(type default)
					)
					(fill
						(type none)
					)
				)
				(polyline
					(pts
						(xy 2.54 1.016) (xy 2.54 -1.016)
					)
					(stroke
						(width 0.254)
						(type default)
					)
					(fill
						(type none)
					)
				)
				(polyline
					(pts
						(xy 2.921 -1.016) (xy 2.54 -1.016)
					)
					(stroke
						(width 0.254)
						(type default)
					)
					(fill
						(type none)
					)
				)
				(polyline
					(pts
						(xy 4.064 1.016) (xy 4.064 -1.016) (xy 2.54 0) (xy 4.064 1.016)
					)
					(stroke
						(width 0.254)
						(type default)
					)
					(fill
						(type outline)
					)
				)
				(pin passive line
					(at 0 0 0)
					(length 0.635)
					(name "C"
						(effects
							(font
								(size 1.27 1.27)
							)
						)
					)
					(number "1"
						(effects
							(font
								(size 1.27 1.27)
							)
						)
					)
				)
				(pin passive line
					(at 5.08 0 180)
					(length 0.635)
					(name "A"
						(effects
							(font
								(size 1.27 1.27)
							)
						)
					)
					(number "2"
						(effects
							(font
								(size 1.27 1.27)
							)
						)
					)
				)
			)
		)
	(symbol "antmicroTVSDiodes:SZSMF4L14AT3G"
			(pin_numbers
				(hide yes)
			)
			(pin_names
				(hide yes)
			)
			(exclude_from_sim no)
			(in_bom yes)
			(on_board yes)
			(property "Reference" "D"
				(at 15.24 -5.08 0)
				(effects
					(font
						(size 1.27 1.27)
						(thickness 0.15)
					)
					(justify left bottom)
				)
			)
			(property "Value" "SZSMF4L14AT3G"
				(at 15.24 -10.16 0)
				(effects
					(font
						(size 1.27 1.27)
						(thickness 0.15)
					)
					(justify left bottom)
					(hide yes)
				)
			)
			(property "Footprint" "antmicro-footprints:SOD-123FL"
				(at 15.24 -12.7 0)
				(effects
					(font
						(size 1.27 1.27)
						(thickness 0.15)
					)
					(justify left bottom)
					(hide yes)
				)
			)
			(property "Datasheet" "https://www.mouser.com/datasheet/2/240/media-3320461.pdf"
				(at 15.24 -15.24 0)
				(effects
					(font
						(size 1.27 1.27)
						(thickness 0.15)
					)
					(justify left bottom)
					(hide yes)
				)
			)
			(property "Description" "ESD, TVS Diode, 14V, UNI, 400W, SOD-123FL"
				(at 0 0 0)
				(effects
					(font
						(size 1.27 1.27)
					)
					(hide yes)
				)
			)
			(property "MPN" "SZSMF4L12AT3G"
				(at 15.24 -7.62 0)
				(effects
					(font
						(size 1.27 1.27)
						(thickness 0.15)
					)
					(justify left bottom)
				)
			)
			(property "Author" "Antmicro"
				(at 15.24 -17.78 0)
				(effects
					(font
						(size 1.27 1.27)
						(thickness 0.15)
					)
					(justify left bottom)
					(hide yes)
				)
			)
			(property "License" "Apache-2.0"
				(at 15.24 -20.32 0)
				(effects
					(font
						(size 1.27 1.27)
						(thickness 0.15)
					)
					(justify left bottom)
					(hide yes)
				)
			)
			(property "Manufacturer" "Littelfuse"
				(at 15.24 -22.86 0)
				(effects
					(font
						(size 1.27 1.27)
						(thickness 0.15)
					)
					(justify left bottom)
					(hide yes)
				)
			)
			(property "ki_keywords" "SMT, DIODE, SEMICONDUCTOR, ESD, TVS"
				(at 0 0 0)
				(effects
					(font
						(size 1.27 1.27)
					)
					(hide yes)
				)
			)
			(symbol "SZSMF4L14AT3G_0_1"
				(polyline
					(pts
						(xy 1.905 0) (xy 0.635 0)
					)
					(stroke
						(width 0)
						(type default)
					)
					(fill
						(type none)
					)
				)
				(polyline
					(pts
						(xy 4.445 0) (xy 3.175 0)
					)
					(stroke
						(width 0)
						(type default)
					)
					(fill
						(type none)
					)
				)
			)
			(symbol "SZSMF4L14AT3G_1_1"
				(polyline
					(pts
						(xy 1.778 1.016) (xy 1.397 1.016)
					)
					(stroke
						(width 0.254)
						(type default)
					)
					(fill
						(type none)
					)
				)
				(polyline
					(pts
						(xy 1.778 1.016) (xy 1.778 -1.016)
					)
					(stroke
						(width 0.254)
						(type default)
					)
					(fill
						(type none)
					)
				)
				(polyline
					(pts
						(xy 2.159 -1.016) (xy 1.778 -1.016)
					)
					(stroke
						(width 0.254)
						(type default)
					)
					(fill
						(type none)
					)
				)
				(polyline
					(pts
						(xy 3.302 1.016) (xy 3.302 -1.016) (xy 1.778 0) (xy 3.302 1.016)
					)
					(stroke
						(width 0.254)
						(type default)
					)
					(fill
						(type outline)
					)
				)
				(pin passive line
					(at 0 0 0)
					(length 0.635)
					(name "C"
						(effects
							(font
								(size 1.27 1.27)
							)
						)
					)
					(number "1"
						(effects
							(font
								(size 1.27 1.27)
							)
						)
					)
				)
				(pin passive line
					(at 5.08 0 180)
					(length 0.635)
					(name "A"
						(effects
							(font
								(size 1.27 1.27)
							)
						)
					)
					(number "2"
						(effects
							(font
								(size 1.27 1.27)
							)
						)
					)
				)
			)
		)
	(symbol "antmicroTVSDiodes:TPD4E02B04DQA"
			(exclude_from_sim no)
			(in_bom yes)
			(on_board yes)
			(property "Reference" "U"
				(at 12.7 0 0)
				(effects
					(font
						(size 1.27 1.27)
						(thickness 0.15)
					)
					(justify left bottom)
				)
			)
			(property "Value" "TPD4E02B04DQA"
				(at 12.7 -10.16 0)
				(effects
					(font
						(size 1.27 1.27)
						(thickness 0.15)
					)
					(justify left bottom)
					(hide yes)
				)
			)
			(property "Footprint" "antmicro-footprints:USON-10_2.5x1mm_P0.5mm"
				(at 12.7 -5.08 0)
				(effects
					(font
						(size 1.27 1.27)
						(thickness 0.15)
					)
					(justify left bottom)
					(hide yes)
				)
			)
			(property "Datasheet" "http://www.ti.com/lit/ds/symlink/tpd4e02b04.pdf"
				(at 12.7 -7.62 0)
				(effects
					(font
						(size 1.27 1.27)
						(thickness 0.15)
					)
					(justify left bottom)
					(hide yes)
				)
			)
			(property "Description" "TVS diode array, 12 kV, USON-10, 3.6 V, 0.33 pF"
				(at 0 0 0)
				(effects
					(font
						(size 1.27 1.27)
					)
					(hide yes)
				)
			)
			(property "MPN" "TPD4E02B04DQAR"
				(at 12.7 -2.54 0)
				(effects
					(font
						(size 1.27 1.27)
						(thickness 0.15)
					)
					(justify left bottom)
				)
			)
			(property "Manufacturer" "Texas Instruments"
				(at 12.7 -12.7 0)
				(effects
					(font
						(size 1.27 1.27)
						(thickness 0.15)
					)
					(justify left bottom)
					(hide yes)
				)
			)
			(property "Author" "Antmicro"
				(at 12.7 -15.24 0)
				(effects
					(font
						(size 1.27 1.27)
						(thickness 0.15)
					)
					(justify left bottom)
					(hide yes)
				)
			)
			(property "License" "Apache-2.0"
				(at 12.7 -17.78 0)
				(effects
					(font
						(size 1.27 1.27)
						(thickness 0.15)
					)
					(justify left bottom)
					(hide yes)
				)
			)
			(property "ki_keywords" "SMT, DIODE, SEMICONDUCTOR, TVS, ESD"
				(at 0 0 0)
				(effects
					(font
						(size 1.27 1.27)
					)
					(hide yes)
				)
			)
			(property "ki_fp_filters" "USON*2.5x1.0mm*P0.5mm*"
				(at 0 0 0)
				(effects
					(font
						(size 1.27 1.27)
					)
					(hide yes)
				)
			)
			(symbol "TPD4E02B04DQA_1_1"
				(rectangle
					(start 2.54 2.54)
					(end 8.89 -11.43)
					(stroke
						(width 0.254)
						(type default)
					)
					(fill
						(type background)
					)
				)
				(polyline
					(pts
						(xy 2.54 0) (xy 7.62 0)
					)
					(stroke
						(width 0.254)
						(type default)
					)
					(fill
						(type background)
					)
				)
				(polyline
					(pts
						(xy 2.54 -2.54) (xy 7.62 -2.54)
					)
					(stroke
						(width 0.254)
						(type default)
					)
					(fill
						(type background)
					)
				)
				(polyline
					(pts
						(xy 2.54 -5.08) (xy 7.62 -5.08)
					)
					(stroke
						(width 0.254)
						(type default)
					)
					(fill
						(type background)
					)
				)
				(polyline
					(pts
						(xy 2.54 -7.62) (xy 7.62 -7.62)
					)
					(stroke
						(width 0.254)
						(type default)
					)
					(fill
						(type background)
					)
				)
				(polyline
					(pts
						(xy 4.826 -0.635) (xy 5.08 -0.381) (xy 5.08 0.381) (xy 5.334 0.635)
					)
					(stroke
						(width 0.254)
						(type default)
					)
					(fill
						(type background)
					)
				)
				(polyline
					(pts
						(xy 4.826 -3.175) (xy 5.08 -2.921) (xy 5.08 -2.159) (xy 5.334 -1.905)
					)
					(stroke
						(width 0.254)
						(type default)
					)
					(fill
						(type background)
					)
				)
				(polyline
					(pts
						(xy 4.826 -5.715) (xy 5.08 -5.461) (xy 5.08 -4.699) (xy 5.334 -4.445)
					)
					(stroke
						(width 0.254)
						(type default)
					)
					(fill
						(type background)
					)
				)
				(polyline
					(pts
						(xy 4.826 -8.255) (xy 5.08 -8.001) (xy 5.08 -7.239) (xy 5.334 -6.985)
					)
					(stroke
						(width 0.254)
						(type default)
					)
					(fill
						(type background)
					)
				)
				(polyline
					(pts
						(xy 5.08 0) (xy 3.81 -0.635) (xy 3.81 0.635) (xy 5.08 0)
					)
					(stroke
						(width 0.254)
						(type default)
					)
					(fill
						(type background)
					)
				)
				(polyline
					(pts
						(xy 5.08 0) (xy 6.35 -0.635) (xy 6.35 0.635) (xy 5.08 0)
					)
					(stroke
						(width 0.254)
						(type default)
					)
					(fill
						(type background)
					)
				)
				(polyline
					(pts
						(xy 5.08 -2.54) (xy 3.81 -3.175) (xy 3.81 -1.905) (xy 5.08 -2.54)
					)
					(stroke
						(width 0.254)
						(type default)
					)
					(fill
						(type background)
					)
				)
				(polyline
					(pts
						(xy 5.08 -2.54) (xy 6.35 -3.175) (xy 6.35 -1.905) (xy 5.08 -2.54)
					)
					(stroke
						(width 0.254)
						(type default)
					)
					(fill
						(type background)
					)
				)
				(polyline
					(pts
						(xy 5.08 -5.08) (xy 3.81 -5.715) (xy 3.81 -4.445) (xy 5.08 -5.08)
					)
					(stroke
						(width 0.254)
						(type default)
					)
					(fill
						(type background)
					)
				)
				(polyline
					(pts
						(xy 5.08 -5.08) (xy 6.35 -4.445) (xy 6.35 -5.715) (xy 5.08 -5.08)
					)
					(stroke
						(width 0.254)
						(type default)
					)
					(fill
						(type background)
					)
				)
				(polyline
					(pts
						(xy 5.08 -7.62) (xy 3.81 -8.255) (xy 3.81 -6.985) (xy 5.08 -7.62)
					)
					(stroke
						(width 0.254)
						(type default)
					)
					(fill
						(type background)
					)
				)
				(polyline
					(pts
						(xy 6.35 -6.985) (xy 6.35 -8.255) (xy 5.08 -7.62) (xy 6.35 -6.985)
					)
					(stroke
						(width 0.254)
						(type default)
					)
					(fill
						(type background)
					)
				)
				(polyline
					(pts
						(xy 7.62 0) (xy 7.62 -10.16)
					)
					(stroke
						(width 0.254)
						(type default)
					)
					(fill
						(type background)
					)
				)
				(circle
					(center 7.62 -2.54)
					(radius 0.254)
					(stroke
						(width 0.254)
						(type default)
					)
					(fill
						(type background)
					)
				)
				(circle
					(center 7.62 -5.08)
					(radius 0.254)
					(stroke
						(width 0.254)
						(type default)
					)
					(fill
						(type background)
					)
				)
				(circle
					(center 7.62 -5.08)
					(radius 0.254)
					(stroke
						(width 0.254)
						(type default)
					)
					(fill
						(type background)
					)
				)
				(circle
					(center 7.62 -7.62)
					(radius 0.254)
					(stroke
						(width 0.254)
						(type default)
					)
					(fill
						(type background)
					)
				)
				(polyline
					(pts
						(xy 7.62 -10.16) (xy 2.54 -10.16)
					)
					(stroke
						(width 0.254)
						(type default)
					)
					(fill
						(type background)
					)
				)
				(pin passive line
					(at 0 0 0)
					(length 2.54)
					(name "~"
						(effects
							(font
								(size 1.27 1.27)
							)
						)
					)
					(number "1"
						(effects
							(font
								(size 1.27 1.27)
							)
						)
					)
				)
				(pin passive line
					(at 0 0 0)
					(length 2.54)
					(hide yes)
					(name "~"
						(effects
							(font
								(size 1.27 1.27)
							)
						)
					)
					(number "10"
						(effects
							(font
								(size 1.27 1.27)
							)
						)
					)
				)
				(pin passive line
					(at 0 -2.54 0)
					(length 2.54)
					(name "~"
						(effects
							(font
								(size 1.27 1.27)
							)
						)
					)
					(number "2"
						(effects
							(font
								(size 1.27 1.27)
							)
						)
					)
				)
				(pin passive line
					(at 0 -2.54 0)
					(length 2.54)
					(hide yes)
					(name "~"
						(effects
							(font
								(size 1.27 1.27)
							)
						)
					)
					(number "9"
						(effects
							(font
								(size 1.27 1.27)
							)
						)
					)
				)
				(pin passive line
					(at 0 -5.08 0)
					(length 2.54)
					(name "~"
						(effects
							(font
								(size 1.27 1.27)
							)
						)
					)
					(number "4"
						(effects
							(font
								(size 1.27 1.27)
							)
						)
					)
				)
				(pin passive line
					(at 0 -5.08 0)
					(length 2.54)
					(hide yes)
					(name "~"
						(effects
							(font
								(size 1.27 1.27)
							)
						)
					)
					(number "7"
						(effects
							(font
								(size 1.27 1.27)
							)
						)
					)
				)
				(pin passive line
					(at 0 -7.62 0)
					(length 2.54)
					(name "~"
						(effects
							(font
								(size 1.27 1.27)
							)
						)
					)
					(number "5"
						(effects
							(font
								(size 1.27 1.27)
							)
						)
					)
				)
				(pin passive line
					(at 0 -7.62 0)
					(length 2.54)
					(hide yes)
					(name "~"
						(effects
							(font
								(size 1.27 1.27)
							)
						)
					)
					(number "6"
						(effects
							(font
								(size 1.27 1.27)
							)
						)
					)
				)
				(pin power_in line
					(at 0 -10.16 0)
					(length 2.54)
					(name "~"
						(effects
							(font
								(size 1.27 1.27)
							)
						)
					)
					(number "3"
						(effects
							(font
								(size 1.27 1.27)
							)
						)
					)
				)
				(pin passive line
					(at 0 -10.16 0)
					(length 2.54)
					(hide yes)
					(name "~"
						(effects
							(font
								(size 1.27 1.27)
							)
						)
					)
					(number "8"
						(effects
							(font
								(size 1.27 1.27)
							)
						)
					)
				)
			)
		)
	(symbol "antmicroTVSDiodes:TVS2200DRVR"
			(pin_names
				(offset 1.016)
			)
			(exclude_from_sim no)
			(in_bom yes)
			(on_board yes)
			(property "Reference" "U"
				(at 16.51 3.48 0)
				(effects
					(font
						(size 1.27 1.27)
					)
					(justify left bottom)
				)
			)
			(property "Value" "TVS2200DRVR"
				(at 16.51 -8.636 0)
				(effects
					(font
						(size 1.27 1.27)
					)
					(justify left bottom)
					(hide yes)
				)
			)
			(property "Footprint" "antmicro-footprints:WSON-6-1EP_2x2mm_P0.65mm"
				(at 16.51 -2.52 0)
				(effects
					(font
						(size 1.27 1.27)
					)
					(justify left bottom)
					(hide yes)
				)
			)
			(property "Datasheet" "https://www.ti.com/lit/ds/symlink/tvs2200.pdf?ts=1712230685180&ref_url=https%253A%252F%252Fwww.ti.com%252Fproduct%252FTVS2200"
				(at 16.51 -5.52 0)
				(effects
					(font
						(size 1.27 1.27)
					)
					(justify left bottom)
					(hide yes)
				)
			)
			(property "Description" "ESD Protection Device, 1 kV, WSON-6, 22 V, 105 pF"
				(at 0 0 0)
				(effects
					(font
						(size 1.27 1.27)
					)
					(hide yes)
				)
			)
			(property "MPN" "TVS2200DRVR"
				(at 16.51 0.508 0)
				(effects
					(font
						(size 1.27 1.27)
					)
					(justify left bottom)
				)
			)
			(property "Manufacturer" "Texas Instruments"
				(at 16.51 -11.43 0)
				(effects
					(font
						(size 1.27 1.27)
					)
					(justify left bottom)
					(hide yes)
				)
			)
			(property "License" "Apache-2.0"
				(at 16.51 -16.51 0)
				(effects
					(font
						(size 1.27 1.27)
					)
					(justify left bottom)
					(hide yes)
				)
			)
			(property "Author" "Antmicro"
				(at 16.51 -13.97 0)
				(effects
					(font
						(size 1.27 1.27)
					)
					(justify left bottom)
					(hide yes)
				)
			)
			(property "ki_keywords" "SMT, DIODE, IC, TVS, ESD"
				(at 0 0 0)
				(effects
					(font
						(size 1.27 1.27)
					)
					(hide yes)
				)
			)
			(symbol "TVS2200DRVR_1_0"
				(rectangle
					(start 2.54 2.54)
					(end 7.62 -5.08)
					(stroke
						(width 0.254)
						(type default)
					)
					(fill
						(type background)
					)
				)
				(pin passive line
					(at 0 0 0)
					(length 2.54)
					(name "IN"
						(effects
							(font
								(size 1.27 1.27)
							)
						)
					)
					(number "4"
						(effects
							(font
								(size 1.27 1.27)
							)
						)
					)
				)
				(pin passive line
					(at 0 0 0)
					(length 2.54)
					(hide yes)
					(name "IN"
						(effects
							(font
								(size 1.27 1.27)
							)
						)
					)
					(number "5"
						(effects
							(font
								(size 1.27 1.27)
							)
						)
					)
				)
				(pin passive line
					(at 0 0 0)
					(length 2.54)
					(hide yes)
					(name "IN"
						(effects
							(font
								(size 1.27 1.27)
							)
						)
					)
					(number "6"
						(effects
							(font
								(size 1.27 1.27)
							)
						)
					)
				)
				(pin passive line
					(at 0 -2.54 0)
					(length 2.54)
					(name "GND"
						(effects
							(font
								(size 1.27 1.27)
							)
						)
					)
					(number "1"
						(effects
							(font
								(size 1.27 1.27)
							)
						)
					)
				)
				(pin passive line
					(at 0 -2.54 0)
					(length 2.54)
					(hide yes)
					(name "GND"
						(effects
							(font
								(size 1.27 1.27)
							)
						)
					)
					(number "2"
						(effects
							(font
								(size 1.27 1.27)
							)
						)
					)
				)
				(pin passive line
					(at 0 -2.54 0)
					(length 2.54)
					(hide yes)
					(name "GND"
						(effects
							(font
								(size 1.27 1.27)
							)
						)
					)
					(number "3"
						(effects
							(font
								(size 1.27 1.27)
							)
						)
					)
				)
				(pin passive line
					(at 0 -2.54 0)
					(length 2.54)
					(hide yes)
					(name "GND"
						(effects
							(font
								(size 1.27 1.27)
							)
						)
					)
					(number "7"
						(effects
							(font
								(size 1.27 1.27)
							)
						)
					)
				)
			)
		)
	(symbol "antmicroTestPoints:TP_0.75mm_SMD"
			(pin_names
				(hide yes)
			)
			(exclude_from_sim no)
			(in_bom no)
			(on_board yes)
			(property "Reference" "TP"
				(at 10.16 -1.27 0)
				(effects
					(font
						(size 1.27 1.27)
						(thickness 0.15)
					)
					(justify left bottom)
				)
			)
			(property "Value" "TP_0.75mm_SMD"
				(at 10.16 -3.81 0)
				(effects
					(font
						(size 1.27 1.27)
						(thickness 0.15)
					)
					(justify left bottom)
					(hide yes)
				)
			)
			(property "Footprint" "antmicro-footprints:TP_SMD_0.75mm"
				(at 10.16 -6.35 0)
				(effects
					(font
						(size 1.27 1.27)
						(thickness 0.15)
					)
					(justify left bottom)
					(hide yes)
				)
			)
			(property "Datasheet" ""
				(at 17.78 -12.7 0)
				(effects
					(font
						(size 1.27 1.27)
						(thickness 0.15)
					)
					(justify left bottom)
					(hide yes)
				)
			)
			(property "Description" "SMT test point"
				(at 0 0 0)
				(effects
					(font
						(size 1.27 1.27)
					)
					(hide yes)
				)
			)
			(property "MPN" ""
				(at 10.795 -11.43 0)
				(effects
					(font
						(size 1.27 1.27)
						(thickness 0.15)
					)
					(justify left bottom)
					(hide yes)
				)
			)
			(property "Manufacturer" ""
				(at 10.795 -6.35 0)
				(effects
					(font
						(size 1.27 1.27)
						(thickness 0.15)
					)
					(justify left bottom)
					(hide yes)
				)
			)
			(property "Author" "Antmicro"
				(at 10.16 -8.89 0)
				(effects
					(font
						(size 1.27 1.27)
						(thickness 0.15)
					)
					(justify left bottom)
					(hide yes)
				)
			)
			(property "License" "Apache-2.0"
				(at 10.16 -11.43 0)
				(effects
					(font
						(size 1.27 1.27)
						(thickness 0.15)
					)
					(justify left bottom)
					(hide yes)
				)
			)
			(property "ki_keywords" "TESTPOINT"
				(at 0 0 0)
				(effects
					(font
						(size 1.27 1.27)
					)
					(hide yes)
				)
			)
			(symbol "TP_0.75mm_SMD_1_1"
				(circle
					(center 3.175 0)
					(radius 0.635)
					(stroke
						(width 0.254)
						(type default)
					)
					(fill
						(type none)
					)
				)
				(pin passive line
					(at 0 0 0)
					(length 2.54)
					(name "1"
						(effects
							(font
								(size 1.27 1.27)
							)
						)
					)
					(number "1"
						(effects
							(font
								(size 1.27 1.27)
							)
						)
					)
				)
			)
		)
	(symbol "antmicroTransistorsFETsMOSFETsSingle:SQS401EN-T1_BE3"
			(pin_names
				(offset 0)
			)
			(exclude_from_sim no)
			(in_bom no)
			(on_board yes)
			(property "Reference" "Q"
				(at 15.24 -5.08 0)
				(effects
					(font
						(size 1.27 1.27)
						(thickness 0.15)
					)
					(justify left bottom)
				)
			)
			(property "Value" "SQS401EN-T1_BE3"
				(at 15.24 -10.16 0)
				(effects
					(font
						(size 1.27 1.27)
						(thickness 0.15)
					)
					(justify left bottom)
					(hide yes)
				)
			)
			(property "Footprint" "antmicro-footprints:Vishay_PowerPAK_1212-8_Single"
				(at 15.24 -12.7 0)
				(effects
					(font
						(size 1.27 1.27)
						(thickness 0.15)
					)
					(justify left bottom)
					(hide yes)
				)
			)
			(property "Datasheet" "https://www.vishay.com/docs/65529/sqs401en.pdf"
				(at 15.24 -15.24 0)
				(effects
					(font
						(size 1.27 1.27)
						(thickness 0.15)
					)
					(justify left bottom)
					(hide yes)
				)
			)
			(property "Description" "MOSFET, P Channel, 40 V, 16A, 0.047 ohm, PowerPAK 1212-8, Surface Mount"
				(at 53.34 -24.384 0)
				(effects
					(font
						(size 1.27 1.27)
					)
					(hide yes)
				)
			)
			(property "MPN" "SQS401EN-T1_BE3"
				(at 15.24 -7.62 0)
				(effects
					(font
						(size 1.27 1.27)
						(thickness 0.15)
					)
					(justify left bottom)
				)
			)
			(property "Manufacturer" "Vishay"
				(at 15.24 -17.78 0)
				(effects
					(font
						(size 1.27 1.27)
						(thickness 0.15)
					)
					(justify left bottom)
					(hide yes)
				)
			)
			(property "Author" "Antmicro"
				(at 15.24 -20.32 0)
				(effects
					(font
						(size 1.27 1.27)
						(thickness 0.15)
					)
					(justify left bottom)
					(hide yes)
				)
			)
			(property "License" "Apache-2.0"
				(at 15.24 -22.86 0)
				(effects
					(font
						(size 1.27 1.27)
						(thickness 0.15)
					)
					(justify left bottom)
					(hide yes)
				)
			)
			(property "ki_keywords" "SMT, TRANSISTOR, SEMICONDUCTOR, MOSFET, PMOS"
				(at 0 0 0)
				(effects
					(font
						(size 1.27 1.27)
					)
					(hide yes)
				)
			)
			(symbol "SQS401EN-T1_BE3_1_1"
				(polyline
					(pts
						(xy 1.27 0) (xy 3.302 0) (xy 3.302 3.937)
					)
					(stroke
						(width 0.254)
						(type default)
					)
					(fill
						(type none)
					)
				)
				(polyline
					(pts
						(xy 3.81 4.445) (xy 3.81 3.429)
					)
					(stroke
						(width 0.254)
						(type default)
					)
					(fill
						(type background)
					)
				)
				(polyline
					(pts
						(xy 3.81 2.54) (xy 3.81 3.048)
					)
					(stroke
						(width 0.254)
						(type default)
					)
					(fill
						(type background)
					)
				)
				(polyline
					(pts
						(xy 3.81 2.54) (xy 3.81 2.032)
					)
					(stroke
						(width 0.254)
						(type default)
					)
					(fill
						(type background)
					)
				)
				(polyline
					(pts
						(xy 3.81 1.143) (xy 3.81 1.651)
					)
					(stroke
						(width 0.254)
						(type default)
					)
					(fill
						(type background)
					)
				)
				(polyline
					(pts
						(xy 3.81 1.143) (xy 3.81 0.635)
					)
					(stroke
						(width 0.254)
						(type default)
					)
					(fill
						(type background)
					)
				)
				(circle
					(center 5.08 2.54)
					(radius 3.302)
					(stroke
						(width 0.254)
						(type default)
					)
					(fill
						(type background)
					)
				)
				(polyline
					(pts
						(xy 6.096 2.54) (xy 5.334 2.032) (xy 5.334 3.048) (xy 6.096 2.54)
					)
					(stroke
						(width 0.254)
						(type default)
					)
					(fill
						(type outline)
					)
				)
				(polyline
					(pts
						(xy 6.223 0.635) (xy 7.366 0.635) (xy 7.366 3.937) (xy 7.366 4.445) (xy 6.223 4.445)
					)
					(stroke
						(width 0.254)
						(type default)
					)
					(fill
						(type none)
					)
				)
				(polyline
					(pts
						(xy 6.35 6.35) (xy 6.35 3.937) (xy 3.81 3.937)
					)
					(stroke
						(width 0.254)
						(type default)
					)
					(fill
						(type none)
					)
				)
				(circle
					(center 6.35 4.445)
					(radius 0.127)
					(stroke
						(width 0.254)
						(type default)
					)
					(fill
						(type background)
					)
				)
				(polyline
					(pts
						(xy 6.35 1.143) (xy 3.81 1.143)
					)
					(stroke
						(width 0.254)
						(type default)
					)
					(fill
						(type background)
					)
				)
				(circle
					(center 6.35 1.143)
					(radius 0.127)
					(stroke
						(width 0.254)
						(type default)
					)
					(fill
						(type background)
					)
				)
				(circle
					(center 6.35 0.635)
					(radius 0.127)
					(stroke
						(width 0.254)
						(type default)
					)
					(fill
						(type background)
					)
				)
				(polyline
					(pts
						(xy 6.35 -1.27) (xy 6.35 2.54) (xy 3.81 2.54)
					)
					(stroke
						(width 0.254)
						(type default)
					)
					(fill
						(type none)
					)
				)
				(polyline
					(pts
						(xy 7.366 2.286) (xy 7.874 3.048) (xy 6.858 3.048) (xy 7.366 2.286)
					)
					(stroke
						(width 0.254)
						(type default)
					)
					(fill
						(type outline)
					)
				)
				(polyline
					(pts
						(xy 7.874 2.286) (xy 6.858 2.286)
					)
					(stroke
						(width 0.254)
						(type default)
					)
					(fill
						(type background)
					)
				)
				(pin input line
					(at 0 0 0)
					(length 2.54)
					(name "G"
						(effects
							(font
								(size 1.27 1.27)
							)
						)
					)
					(number "4"
						(effects
							(font
								(size 1.27 1.27)
							)
						)
					)
				)
				(pin passive line
					(at 6.35 7.62 270)
					(length 2.54)
					(name "D"
						(effects
							(font
								(size 1.27 1.27)
							)
						)
					)
					(number "5"
						(effects
							(font
								(size 1.27 1.27)
							)
						)
					)
				)
				(pin passive line
					(at 6.35 -2.54 90)
					(length 2.54)
					(name "S"
						(effects
							(font
								(size 1.27 1.27)
							)
						)
					)
					(number "1"
						(effects
							(font
								(size 1.27 1.27)
							)
						)
					)
				)
				(pin passive line
					(at 6.35 -2.54 90)
					(length 2.54)
					(hide yes)
					(name "S"
						(effects
							(font
								(size 1.27 1.27)
							)
						)
					)
					(number "2"
						(effects
							(font
								(size 1.27 1.27)
							)
						)
					)
				)
				(pin passive line
					(at 6.35 -2.54 90)
					(length 2.54)
					(hide yes)
					(name "S"
						(effects
							(font
								(size 1.27 1.27)
							)
						)
					)
					(number "3"
						(effects
							(font
								(size 1.27 1.27)
							)
						)
					)
				)
			)
		)
	(symbol "antmicroUSBConnectors:USB-C_GCT_USB4105-GF-A"
			(exclude_from_sim no)
			(in_bom yes)
			(on_board yes)
			(property "Reference" "J"
				(at 38.1 -2.54 0)
				(effects
					(font
						(size 1.27 1.27)
						(thickness 0.15)
					)
					(justify left bottom)
				)
			)
			(property "Value" "USB-C_GCT_USB4105-GF-A"
				(at 38.1 -5.08 0)
				(effects
					(font
						(size 1.27 1.27)
						(thickness 0.15)
					)
					(justify left bottom)
					(hide yes)
				)
			)
			(property "Footprint" "antmicro-footprints:USB-C_Receptacle_GCT_USB4105-GF-A"
				(at 38.1 -7.62 0)
				(effects
					(font
						(size 1.27 1.27)
						(thickness 0.15)
					)
					(justify left bottom)
					(hide yes)
				)
			)
			(property "Datasheet" "https://gct.co/files/drawings/usb4105.pdf"
				(at 38.1 -10.16 0)
				(effects
					(font
						(size 1.27 1.27)
						(thickness 0.15)
					)
					(justify left bottom)
					(hide yes)
				)
			)
			(property "Description" "USB-C (USB TYPE-C) USB 2.0 Receptacle Connector 24 (16+8 Dummy) Position Surface Mount, Right Angle"
				(at 38.1 -22.86 0)
				(effects
					(font
						(size 1.27 1.27)
					)
					(justify left bottom)
					(hide yes)
				)
			)
			(property "Manufacturer" "GCT"
				(at 38.1 -12.7 0)
				(effects
					(font
						(size 1.27 1.27)
						(thickness 0.15)
					)
					(justify left bottom)
					(hide yes)
				)
			)
			(property "MPN" "USB4105-GF-A"
				(at 38.1 -15.24 0)
				(effects
					(font
						(size 1.27 1.27)
						(thickness 0.15)
					)
					(justify left bottom)
				)
			)
			(property "Author" "Antmicro"
				(at 38.1 -17.78 0)
				(effects
					(font
						(size 1.27 1.27)
						(thickness 0.15)
					)
					(justify left bottom)
					(hide yes)
				)
			)
			(property "License" "Apache-2.0"
				(at 38.1 -20.32 0)
				(effects
					(font
						(size 1.27 1.27)
						(thickness 0.15)
					)
					(justify left bottom)
					(hide yes)
				)
			)
			(property "ki_keywords" "USB, CONNECTOR, SMT, HORIZONTAL"
				(at 0 0 0)
				(effects
					(font
						(size 1.27 1.27)
					)
					(hide yes)
				)
			)
			(symbol "USB-C_GCT_USB4105-GF-A_1_1"
				(rectangle
					(start -22.86 2.54)
					(end -3.81 -38.1)
					(stroke
						(width 0.254)
						(type default)
					)
					(fill
						(type background)
					)
				)
				(circle
					(center -20.066 -18.034)
					(radius 0.284)
					(stroke
						(width 0.254)
						(type default)
					)
					(fill
						(type outline)
					)
				)
				(polyline
					(pts
						(xy -19.812 -16.383) (xy -19.177 -15.24) (xy -18.542 -16.383) (xy -19.812 -16.383)
					)
					(stroke
						(width 0.254)
						(type default)
					)
					(fill
						(type outline)
					)
				)
				(polyline
					(pts
						(xy -19.177 -19.558) (xy -18.288 -18.669) (xy -18.288 -18.034)
					)
					(stroke
						(width 0.254)
						(type default)
					)
					(fill
						(type background)
					)
				)
				(polyline
					(pts
						(xy -19.177 -19.939) (xy -20.066 -19.05) (xy -20.066 -18.415)
					)
					(stroke
						(width 0.254)
						(type default)
					)
					(fill
						(type background)
					)
				)
				(polyline
					(pts
						(xy -19.177 -20.701) (xy -19.177 -16.383)
					)
					(stroke
						(width 0.254)
						(type default)
					)
					(fill
						(type background)
					)
				)
				(circle
					(center -19.177 -20.828)
					(radius 0.5236)
					(stroke
						(width 0.254)
						(type default)
					)
					(fill
						(type outline)
					)
				)
				(rectangle
					(start -18.669 -18.034)
					(end -17.907 -17.272)
					(stroke
						(width 0.254)
						(type default)
					)
					(fill
						(type outline)
					)
				)
				(polyline
					(pts
						(xy -16.51 -21.59) (xy -16.51 -13.97)
					)
					(stroke
						(width 0.254)
						(type default)
					)
					(fill
						(type background)
					)
				)
				(rectangle
					(start -15.24 -21.59)
					(end -13.97 -13.97)
					(stroke
						(width 0.254)
						(type default)
					)
					(fill
						(type outline)
					)
				)
				(arc
					(start -15.24 -13.97)
					(mid -14.605 -13.3377)
					(end -13.97 -13.97)
					(stroke
						(width 0.254)
						(type default)
					)
					(fill
						(type outline)
					)
				)
				(arc
					(start -15.24 -13.97)
					(mid -14.605 -13.3377)
					(end -13.97 -13.97)
					(stroke
						(width 0.254)
						(type default)
					)
					(fill
						(type background)
					)
				)
				(arc
					(start -16.51 -13.97)
					(mid -14.605 -12.0733)
					(end -12.7 -13.97)
					(stroke
						(width 0.254)
						(type default)
					)
					(fill
						(type background)
					)
				)
				(arc
					(start -12.7 -21.59)
					(mid -14.605 -23.4867)
					(end -16.51 -21.59)
					(stroke
						(width 0.254)
						(type default)
					)
					(fill
						(type background)
					)
				)
				(arc
					(start -13.97 -21.59)
					(mid -14.605 -22.2223)
					(end -15.24 -21.59)
					(stroke
						(width 0.254)
						(type default)
					)
					(fill
						(type outline)
					)
				)
				(arc
					(start -13.97 -21.59)
					(mid -14.605 -22.2223)
					(end -15.24 -21.59)
					(stroke
						(width 0.254)
						(type default)
					)
					(fill
						(type background)
					)
				)
				(polyline
					(pts
						(xy -12.7 -13.97) (xy -12.7 -21.59)
					)
					(stroke
						(width 0.254)
						(type default)
					)
					(fill
						(type background)
					)
				)
				(pin power_in line
					(at 0 0 180)
					(length 3.81)
					(name "VBUS"
						(effects
							(font
								(size 1.27 1.27)
							)
						)
					)
					(number "A4"
						(effects
							(font
								(size 1.27 1.27)
							)
						)
					)
				)
				(pin passive line
					(at 0 0 180)
					(length 3.81)
					(hide yes)
					(name "VBUS"
						(effects
							(font
								(size 1.27 1.27)
							)
						)
					)
					(number "A9"
						(effects
							(font
								(size 1.27 1.27)
							)
						)
					)
				)
				(pin passive line
					(at 0 0 180)
					(length 3.81)
					(hide yes)
					(name "VBUS"
						(effects
							(font
								(size 1.27 1.27)
							)
						)
					)
					(number "B4"
						(effects
							(font
								(size 1.27 1.27)
							)
						)
					)
				)
				(pin passive line
					(at 0 0 180)
					(length 3.81)
					(hide yes)
					(name "VBUS"
						(effects
							(font
								(size 1.27 1.27)
							)
						)
					)
					(number "B9"
						(effects
							(font
								(size 1.27 1.27)
							)
						)
					)
				)
				(pin bidirectional line
					(at 0 -5.08 180)
					(length 3.81)
					(name "CC_{1}"
						(effects
							(font
								(size 1.27 1.27)
							)
						)
					)
					(number "A5"
						(effects
							(font
								(size 1.27 1.27)
							)
						)
					)
				)
				(pin bidirectional line
					(at 0 -7.62 180)
					(length 3.81)
					(name "CC_{2}"
						(effects
							(font
								(size 1.27 1.27)
							)
						)
					)
					(number "B5"
						(effects
							(font
								(size 1.27 1.27)
							)
						)
					)
				)
				(pin bidirectional line
					(at 0 -12.7 180)
					(length 3.81)
					(name "D_{A}+"
						(effects
							(font
								(size 1.27 1.27)
							)
						)
					)
					(number "A6"
						(effects
							(font
								(size 1.27 1.27)
							)
						)
					)
				)
				(pin bidirectional line
					(at 0 -15.24 180)
					(length 3.81)
					(name "D_{A}-"
						(effects
							(font
								(size 1.27 1.27)
							)
						)
					)
					(number "A7"
						(effects
							(font
								(size 1.27 1.27)
							)
						)
					)
				)
				(pin bidirectional line
					(at 0 -17.78 180)
					(length 3.81)
					(name "D_{B}+"
						(effects
							(font
								(size 1.27 1.27)
							)
						)
					)
					(number "B6"
						(effects
							(font
								(size 1.27 1.27)
							)
						)
					)
				)
				(pin bidirectional line
					(at 0 -20.32 180)
					(length 3.81)
					(name "D_{B}-"
						(effects
							(font
								(size 1.27 1.27)
							)
						)
					)
					(number "B7"
						(effects
							(font
								(size 1.27 1.27)
							)
						)
					)
				)
				(pin bidirectional line
					(at 0 -25.4 180)
					(length 3.81)
					(name "SBU_{1}"
						(effects
							(font
								(size 1.27 1.27)
							)
						)
					)
					(number "A8"
						(effects
							(font
								(size 1.27 1.27)
							)
						)
					)
				)
				(pin bidirectional line
					(at 0 -27.94 180)
					(length 3.81)
					(name "SBU_{2}"
						(effects
							(font
								(size 1.27 1.27)
							)
						)
					)
					(number "B8"
						(effects
							(font
								(size 1.27 1.27)
							)
						)
					)
				)
				(pin power_in line
					(at 0 -33.02 180)
					(length 3.81)
					(name "GND"
						(effects
							(font
								(size 1.27 1.27)
							)
						)
					)
					(number "A1"
						(effects
							(font
								(size 1.27 1.27)
							)
						)
					)
				)
				(pin passive line
					(at 0 -33.02 180)
					(length 3.81)
					(hide yes)
					(name "GND"
						(effects
							(font
								(size 1.27 1.27)
							)
						)
					)
					(number "A12"
						(effects
							(font
								(size 1.27 1.27)
							)
						)
					)
				)
				(pin passive line
					(at 0 -33.02 180)
					(length 3.81)
					(hide yes)
					(name "GND"
						(effects
							(font
								(size 1.27 1.27)
							)
						)
					)
					(number "B1"
						(effects
							(font
								(size 1.27 1.27)
							)
						)
					)
				)
				(pin passive line
					(at 0 -33.02 180)
					(length 3.81)
					(hide yes)
					(name "GND"
						(effects
							(font
								(size 1.27 1.27)
							)
						)
					)
					(number "B12"
						(effects
							(font
								(size 1.27 1.27)
							)
						)
					)
				)
				(pin passive line
					(at 0 -35.56 180)
					(length 3.81)
					(name "SH"
						(effects
							(font
								(size 1.27 1.27)
							)
						)
					)
					(number "SH"
						(effects
							(font
								(size 1.27 1.27)
							)
						)
					)
				)
			)
		)
	(symbol "antmicroWire2BoardConnectors:JST_SH_1x4_SM04B-SRSS-TB-LF-SN"
			(exclude_from_sim no)
			(in_bom yes)
			(on_board yes)
			(property "Reference" "J"
				(at 26.67 -2.54 0)
				(effects
					(font
						(size 1.27 1.27)
						(thickness 0.15)
					)
					(justify left bottom)
				)
			)
			(property "Value" "JST_SH_1x4_SM04B-SRSS-TB-LF-SN"
				(at 26.67 -7.62 0)
				(effects
					(font
						(size 1.27 1.27)
						(thickness 0.15)
					)
					(justify left bottom)
					(hide yes)
				)
			)
			(property "Footprint" "antmicro-footprints:Conn_JST_SH_1x4_SM04B-SRSS-TB-LF-SN"
				(at 26.67 -10.16 0)
				(effects
					(font
						(size 1.27 1.27)
						(thickness 0.15)
					)
					(justify left bottom)
					(hide yes)
				)
			)
			(property "Datasheet" "https://www.jst-mfg.com/product/pdf/eng/eSH.pdf"
				(at 26.67 -12.7 0)
				(effects
					(font
						(size 1.27 1.27)
						(thickness 0.15)
					)
					(justify left bottom)
					(hide yes)
				)
			)
			(property "Description" "Pin Header, Right Angle, Wire-to-Board, 1 mm, 1 Rows, 4 Contacts, Surface Mount Right Angle, SH"
				(at 0 0 0)
				(effects
					(font
						(size 1.27 1.27)
					)
					(hide yes)
				)
			)
			(property "MPN" "SM04B-SRSS-TB(LF)(SN)"
				(at 26.67 -5.08 0)
				(effects
					(font
						(size 1.27 1.27)
						(thickness 0.15)
					)
					(justify left bottom)
				)
			)
			(property "Manufacturer" "JST Automotive Connectors"
				(at 26.67 -15.24 0)
				(effects
					(font
						(size 1.27 1.27)
						(thickness 0.15)
					)
					(justify left bottom)
					(hide yes)
				)
			)
			(property "Author" "Antmicro"
				(at 26.67 -17.78 0)
				(effects
					(font
						(size 1.27 1.27)
						(thickness 0.15)
					)
					(justify left bottom)
					(hide yes)
				)
			)
			(property "License" "Apache-2.0"
				(at 26.67 -20.32 0)
				(effects
					(font
						(size 1.27 1.27)
						(thickness 0.15)
					)
					(justify left bottom)
					(hide yes)
				)
			)
			(property "ki_keywords" "VERTICAL, SMT, WIRE-BOARD, CONNECTOR, MALE, HEADER"
				(at 0 0 0)
				(effects
					(font
						(size 1.27 1.27)
					)
					(hide yes)
				)
			)
			(symbol "JST_SH_1x4_SM04B-SRSS-TB-LF-SN_1_1"
				(rectangle
					(start 2.54 2.54)
					(end 5.08 -12.7)
					(stroke
						(width 0.254)
						(type default)
					)
					(fill
						(type background)
					)
				)
				(rectangle
					(start 2.54 0.127)
					(end 3.81 -0.127)
					(stroke
						(width 0.254)
						(type default)
					)
					(fill
						(type background)
					)
				)
				(rectangle
					(start 2.54 -2.413)
					(end 3.81 -2.667)
					(stroke
						(width 0.254)
						(type default)
					)
					(fill
						(type background)
					)
				)
				(rectangle
					(start 2.54 -4.953)
					(end 3.81 -5.207)
					(stroke
						(width 0.254)
						(type default)
					)
					(fill
						(type background)
					)
				)
				(rectangle
					(start 2.54 -7.493)
					(end 3.81 -7.747)
					(stroke
						(width 0.254)
						(type default)
					)
					(fill
						(type background)
					)
				)
				(rectangle
					(start 2.54 -10.033)
					(end 3.81 -10.287)
					(stroke
						(width 0.254)
						(type default)
					)
					(fill
						(type background)
					)
				)
				(pin passive line
					(at 0 0 0)
					(length 2.54)
					(name "~"
						(effects
							(font
								(size 1.27 1.27)
							)
						)
					)
					(number "1"
						(effects
							(font
								(size 1.27 1.27)
							)
						)
					)
				)
				(pin passive line
					(at 0 -2.54 0)
					(length 2.54)
					(name "~"
						(effects
							(font
								(size 1.27 1.27)
							)
						)
					)
					(number "2"
						(effects
							(font
								(size 1.27 1.27)
							)
						)
					)
				)
				(pin passive line
					(at 0 -5.08 0)
					(length 2.54)
					(name "~"
						(effects
							(font
								(size 1.27 1.27)
							)
						)
					)
					(number "3"
						(effects
							(font
								(size 1.27 1.27)
							)
						)
					)
				)
				(pin passive line
					(at 0 -7.62 0)
					(length 2.54)
					(name "~"
						(effects
							(font
								(size 1.27 1.27)
							)
						)
					)
					(number "4"
						(effects
							(font
								(size 1.27 1.27)
							)
						)
					)
				)
				(pin passive line
					(at 0 -10.16 0)
					(length 2.54)
					(name "~"
						(effects
							(font
								(size 1.27 1.27)
							)
						)
					)
					(number "MP"
						(effects
							(font
								(size 1.27 1.27)
							)
						)
					)
				)
			)
		)
	(symbol "antmicroWire2BoardConnectors:Molex_Nano-Fit_1x2_1053131202"
			(exclude_from_sim no)
			(in_bom yes)
			(on_board yes)
			(property "Reference" "J"
				(at 13.335 -2.54 0)
				(effects
					(font
						(size 1.27 1.27)
						(thickness 0.15)
					)
					(justify left bottom)
				)
			)
			(property "Value" "Molex_Nano-Fit_1x2_1053131202"
				(at 13.335 -5.08 0)
				(effects
					(font
						(size 1.27 1.27)
						(thickness 0.15)
					)
					(justify left bottom)
					(hide yes)
				)
			)
			(property "Footprint" "antmicro-footprints:Conn_Molex_Nano-Fit_1x2_1053131102"
				(at 13.335 -7.62 0)
				(effects
					(font
						(size 1.27 1.27)
						(thickness 0.15)
					)
					(justify left bottom)
					(hide yes)
				)
			)
			(property "Datasheet" "https://tools.molex.com/pdm_docs/ps/PS-105300-100-001.pdf"
				(at 13.335 -10.16 0)
				(effects
					(font
						(size 1.27 1.27)
						(thickness 0.15)
					)
					(justify left bottom)
					(hide yes)
				)
			)
			(property "Description" "Rectangular connector, header, Through Hole, Right Angle 2 position"
				(at 0 0 0)
				(effects
					(font
						(size 1.27 1.27)
					)
					(hide yes)
				)
			)
			(property "Manufacturer" "Molex"
				(at 13.335 -12.7 0)
				(effects
					(font
						(size 1.27 1.27)
						(thickness 0.15)
					)
					(justify left bottom)
					(hide yes)
				)
			)
			(property "MPN" "1053131202"
				(at 13.335 -15.24 0)
				(effects
					(font
						(size 1.27 1.27)
						(thickness 0.15)
					)
					(justify left bottom)
				)
			)
			(property "Author" "Antmicro"
				(at 13.335 -17.78 0)
				(effects
					(font
						(size 1.27 1.27)
						(thickness 0.15)
					)
					(justify left bottom)
					(hide yes)
				)
			)
			(property "License" "Apache-2.0"
				(at 13.335 -20.32 0)
				(effects
					(font
						(size 1.27 1.27)
						(thickness 0.15)
					)
					(justify left bottom)
					(hide yes)
				)
			)
			(property "ki_keywords" "CONNECTOR, THT"
				(at 0 0 0)
				(effects
					(font
						(size 1.27 1.27)
					)
					(hide yes)
				)
			)
			(symbol "Molex_Nano-Fit_1x2_1053131202_1_1"
				(rectangle
					(start 2.54 1.27)
					(end 5.08 -3.81)
					(stroke
						(width 0.254)
						(type default)
					)
					(fill
						(type background)
					)
				)
				(rectangle
					(start 2.54 0.127)
					(end 3.81 -0.127)
					(stroke
						(width 0.254)
						(type default)
					)
					(fill
						(type background)
					)
				)
				(rectangle
					(start 2.54 -2.413)
					(end 3.81 -2.667)
					(stroke
						(width 0.254)
						(type default)
					)
					(fill
						(type background)
					)
				)
				(pin input line
					(at 0 0 0)
					(length 2.54)
					(name "~"
						(effects
							(font
								(size 1.27 1.27)
							)
						)
					)
					(number "1"
						(effects
							(font
								(size 1.27 1.27)
							)
						)
					)
				)
				(pin input line
					(at 0 -2.54 0)
					(length 2.54)
					(name "~"
						(effects
							(font
								(size 1.27 1.27)
							)
						)
					)
					(number "2"
						(effects
							(font
								(size 1.27 1.27)
							)
						)
					)
				)
			)
		)
	(symbol "antmicropower:+12V"
			(power)
			(pin_names
				(offset 0)
			)
			(exclude_from_sim no)
			(in_bom yes)
			(on_board yes)
			(property "Reference" "#PWR"
				(at 0 -3.81 0)
				(effects
					(font
						(size 1.27 1.27)
					)
					(hide yes)
				)
			)
			(property "Value" "+12V"
				(at 0 3.556 0)
				(effects
					(font
						(size 1.27 1.27)
					)
				)
			)
			(property "Footprint" ""
				(at 0 0 0)
				(effects
					(font
						(size 1.27 1.27)
					)
					(hide yes)
				)
			)
			(property "Datasheet" ""
				(at 0 0 0)
				(effects
					(font
						(size 1.27 1.27)
					)
					(hide yes)
				)
			)
			(property "Description" ""
				(at 0 0 0)
				(effects
					(font
						(size 1.27 1.27)
					)
					(hide yes)
				)
			)
			(symbol "+12V_0_1"
				(polyline
					(pts
						(xy -0.762 1.27) (xy 0 2.54)
					)
					(stroke
						(width 0)
						(type default)
					)
					(fill
						(type none)
					)
				)
				(polyline
					(pts
						(xy 0 2.54) (xy 0.762 1.27)
					)
					(stroke
						(width 0)
						(type default)
					)
					(fill
						(type none)
					)
				)
				(polyline
					(pts
						(xy 0 0) (xy 0 2.54)
					)
					(stroke
						(width 0)
						(type default)
					)
					(fill
						(type none)
					)
				)
			)
			(symbol "+12V_1_1"
				(pin power_in line
					(at 0 0 90)
					(length 0)
					(hide yes)
					(name "+12V"
						(effects
							(font
								(size 1.27 1.27)
							)
						)
					)
					(number "1"
						(effects
							(font
								(size 1.27 1.27)
							)
						)
					)
				)
			)
		)
	(symbol "antmicropower:+3V3"
			(power)
			(pin_numbers
				(hide yes)
			)
			(pin_names
				(hide yes)
			)
			(exclude_from_sim no)
			(in_bom yes)
			(on_board yes)
			(property "Reference" "#PWR"
				(at 15.24 0 0)
				(effects
					(font
						(size 1.27 1.27)
						(thickness 0.15)
					)
					(justify left bottom)
					(hide yes)
				)
			)
			(property "Value" "+3V3"
				(at -3.175 2.54 0)
				(effects
					(font
						(size 1.27 1.27)
						(thickness 0.15)
					)
					(justify left bottom)
				)
			)
			(property "Footprint" ""
				(at 15.24 -7.62 0)
				(effects
					(font
						(size 1.27 1.27)
						(thickness 0.15)
					)
					(justify left bottom)
					(hide yes)
				)
			)
			(property "Datasheet" ""
				(at 15.24 -10.16 0)
				(effects
					(font
						(size 1.27 1.27)
						(thickness 0.15)
					)
					(justify left bottom)
					(hide yes)
				)
			)
			(property "Description" ""
				(at 0 0 0)
				(effects
					(font
						(size 1.27 1.27)
					)
					(hide yes)
				)
			)
			(property "Author" "Antmicro"
				(at 15.24 -2.54 0)
				(effects
					(font
						(size 1.27 1.27)
						(thickness 0.15)
					)
					(justify left bottom)
					(hide yes)
				)
			)
			(property "License" "Apache-2.0"
				(at 15.24 -5.08 0)
				(effects
					(font
						(size 1.27 1.27)
						(thickness 0.15)
					)
					(justify left bottom)
					(hide yes)
				)
			)
			(symbol "+3V3_0_1"
				(polyline
					(pts
						(xy 0 2.54) (xy -0.762 1.27)
					)
					(stroke
						(width 0)
						(type default)
					)
					(fill
						(type none)
					)
				)
				(polyline
					(pts
						(xy 0 2.54) (xy 0.762 1.27)
					)
					(stroke
						(width 0)
						(type default)
					)
					(fill
						(type none)
					)
				)
				(polyline
					(pts
						(xy 0 0) (xy 0 2.54)
					)
					(stroke
						(width 0)
						(type default)
					)
					(fill
						(type none)
					)
				)
			)
			(symbol "+3V3_1_1"
				(pin power_in line
					(at 0 0 90)
					(length 0)
					(hide yes)
					(name "+3V3"
						(effects
							(font
								(size 1.27 1.27)
							)
						)
					)
					(number "1"
						(effects
							(font
								(size 1.27 1.27)
							)
						)
					)
				)
			)
		)
	(symbol "antmicropower:+5V"
			(power)
			(pin_numbers
				(hide yes)
			)
			(pin_names
				(hide yes)
			)
			(exclude_from_sim no)
			(in_bom yes)
			(on_board yes)
			(property "Reference" "#PWR"
				(at 15.24 -2.54 0)
				(effects
					(font
						(size 1.27 1.27)
						(thickness 0.15)
					)
					(justify left bottom)
					(hide yes)
				)
			)
			(property "Value" "+5V"
				(at 15.24 -5.08 0)
				(effects
					(font
						(size 1.27 1.27)
						(thickness 0.15)
					)
					(justify left bottom)
				)
			)
			(property "Footprint" ""
				(at 15.24 -7.62 0)
				(effects
					(font
						(size 1.27 1.27)
						(thickness 0.15)
					)
					(justify left bottom)
					(hide yes)
				)
			)
			(property "Datasheet" ""
				(at 15.24 -10.16 0)
				(effects
					(font
						(size 1.27 1.27)
						(thickness 0.15)
					)
					(justify left bottom)
					(hide yes)
				)
			)
			(property "Description" ""
				(at 0 0 0)
				(effects
					(font
						(size 1.27 1.27)
					)
					(hide yes)
				)
			)
			(property "Author" "Antmicro"
				(at 15.24 -7.62 0)
				(effects
					(font
						(size 1.27 1.27)
						(thickness 0.15)
					)
					(justify left bottom)
					(hide yes)
				)
			)
			(property "License" "Apache-2.0"
				(at 15.24 -10.16 0)
				(effects
					(font
						(size 1.27 1.27)
						(thickness 0.15)
					)
					(justify left bottom)
					(hide yes)
				)
			)
			(symbol "+5V_1_1"
				(polyline
					(pts
						(xy -0.762 1.27) (xy 0 2.54)
					)
					(stroke
						(width 0)
						(type default)
					)
					(fill
						(type background)
					)
				)
				(polyline
					(pts
						(xy 0 2.54) (xy 0.762 1.27)
					)
					(stroke
						(width 0)
						(type default)
					)
					(fill
						(type background)
					)
				)
				(polyline
					(pts
						(xy 0 0) (xy 0 2.54)
					)
					(stroke
						(width 0)
						(type default)
					)
					(fill
						(type background)
					)
				)
				(pin power_in line
					(at 0 0 90)
					(length 0)
					(name "+5V"
						(effects
							(font
								(size 1.27 1.27)
							)
						)
					)
					(number "1"
						(effects
							(font
								(size 1.27 1.27)
							)
						)
					)
				)
			)
		)
	(symbol "antmicropower:GND"
			(power)
			(pin_numbers
				(hide yes)
			)
			(pin_names
				(hide yes)
			)
			(exclude_from_sim no)
			(in_bom yes)
			(on_board yes)
			(property "Reference" "#PWR"
				(at 8.89 -2.54 0)
				(effects
					(font
						(size 1.27 1.27)
						(thickness 0.15)
					)
					(justify left bottom)
					(hide yes)
				)
			)
			(property "Value" "GND"
				(at 8.89 -5.08 0)
				(effects
					(font
						(size 1.27 1.27)
						(thickness 0.15)
					)
					(justify left bottom)
				)
			)
			(property "Footprint" ""
				(at 8.89 -7.62 0)
				(effects
					(font
						(size 1.27 1.27)
						(thickness 0.15)
					)
					(justify left bottom)
					(hide yes)
				)
			)
			(property "Datasheet" ""
				(at 8.89 -12.7 0)
				(effects
					(font
						(size 1.27 1.27)
						(thickness 0.15)
					)
					(justify left bottom)
					(hide yes)
				)
			)
			(property "Description" ""
				(at 0 0 0)
				(effects
					(font
						(size 1.27 1.27)
					)
					(hide yes)
				)
			)
			(property "Author" "Antmicro"
				(at 8.89 -7.62 0)
				(effects
					(font
						(size 1.27 1.27)
						(thickness 0.15)
					)
					(justify left bottom)
					(hide yes)
				)
			)
			(property "License" "Apache-2.0"
				(at 8.89 -10.16 0)
				(effects
					(font
						(size 1.27 1.27)
						(thickness 0.15)
					)
					(justify left bottom)
					(hide yes)
				)
			)
			(symbol "GND_1_1"
				(polyline
					(pts
						(xy 0 0) (xy 0 -1.27) (xy 1.27 -1.27) (xy 0 -2.54) (xy -1.27 -1.27) (xy 0 -1.27)
					)
					(stroke
						(width 0)
						(type default)
					)
					(fill
						(type none)
					)
				)
				(pin power_in line
					(at 0 0 270)
					(length 0)
					(name "GND"
						(effects
							(font
								(size 1.27 1.27)
							)
						)
					)
					(number "1"
						(effects
							(font
								(size 1.27 1.27)
							)
						)
					)
				)
			)
		)
	(symbol "antmicropower:PWR_FLAG"
			(power)
			(pin_numbers
				(hide yes)
			)
			(pin_names
				(offset 0)
				(hide yes)
			)
			(exclude_from_sim no)
			(in_bom yes)
			(on_board yes)
			(property "Reference" "#FLG"
				(at 0 1.905 0)
				(effects
					(font
						(size 1.27 1.27)
					)
					(hide yes)
				)
			)
			(property "Value" "PWR_FLAG"
				(at 0 3.81 0)
				(effects
					(font
						(size 1.27 1.27)
					)
				)
			)
			(property "Footprint" ""
				(at 0 0 0)
				(effects
					(font
						(size 1.27 1.27)
					)
					(hide yes)
				)
			)
			(property "Datasheet" ""
				(at 0 0 0)
				(effects
					(font
						(size 1.27 1.27)
					)
					(hide yes)
				)
			)
			(property "Description" ""
				(at 0 0 0)
				(effects
					(font
						(size 1.27 1.27)
					)
					(hide yes)
				)
			)
			(symbol "PWR_FLAG_0_0"
				(pin power_out line
					(at 0 0 90)
					(length 0)
					(name "pwr"
						(effects
							(font
								(size 1.27 1.27)
							)
						)
					)
					(number "1"
						(effects
							(font
								(size 1.27 1.27)
							)
						)
					)
				)
			)
			(symbol "PWR_FLAG_0_1"
				(polyline
					(pts
						(xy 0 0) (xy 0 1.27) (xy -1.016 1.905) (xy 0 2.54) (xy 1.016 1.905) (xy 0 1.27)
					)
					(stroke
						(width 0)
						(type default)
					)
					(fill
						(type none)
					)
				)
			)
		)
	(symbol "antmicropower:VBUS"
			(power)
			(pin_names
				(offset 0)
			)
			(exclude_from_sim no)
			(in_bom yes)
			(on_board yes)
			(property "Reference" "#PWR"
				(at 0 -3.81 0)
				(effects
					(font
						(size 1.27 1.27)
					)
					(hide yes)
				)
			)
			(property "Value" "VBUS"
				(at 0 3.81 0)
				(effects
					(font
						(size 1.27 1.27)
					)
				)
			)
			(property "Footprint" ""
				(at 0 0 0)
				(effects
					(font
						(size 1.27 1.27)
					)
					(hide yes)
				)
			)
			(property "Datasheet" ""
				(at 0 0 0)
				(effects
					(font
						(size 1.27 1.27)
					)
					(hide yes)
				)
			)
			(property "Description" ""
				(at 0 0 0)
				(effects
					(font
						(size 1.27 1.27)
					)
					(hide yes)
				)
			)
			(symbol "VBUS_0_1"
				(polyline
					(pts
						(xy -0.762 1.27) (xy 0 2.54)
					)
					(stroke
						(width 0)
						(type default)
					)
					(fill
						(type none)
					)
				)
				(polyline
					(pts
						(xy 0 2.54) (xy 0.762 1.27)
					)
					(stroke
						(width 0)
						(type default)
					)
					(fill
						(type none)
					)
				)
				(polyline
					(pts
						(xy 0 0) (xy 0 2.54)
					)
					(stroke
						(width 0)
						(type default)
					)
					(fill
						(type none)
					)
				)
			)
			(symbol "VBUS_1_1"
				(pin power_in line
					(at 0 0 90)
					(length 0)
					(hide yes)
					(name "VBUS"
						(effects
							(font
								(size 1.27 1.27)
							)
						)
					)
					(number "1"
						(effects
							(font
								(size 1.27 1.27)
							)
						)
					)
				)
			)
		)
	(symbol "antmicropower:VCC"
			(power)
			(pin_names
				(offset 0)
			)
			(exclude_from_sim no)
			(in_bom yes)
			(on_board yes)
			(property "Reference" "#PWR"
				(at 0 -3.81 0)
				(effects
					(font
						(size 1.27 1.27)
					)
					(hide yes)
				)
			)
			(property "Value" "VCC"
				(at 0 3.81 0)
				(effects
					(font
						(size 1.27 1.27)
					)
				)
			)
			(property "Footprint" ""
				(at 0 0 0)
				(effects
					(font
						(size 1.27 1.27)
					)
					(hide yes)
				)
			)
			(property "Datasheet" ""
				(at 0 0 0)
				(effects
					(font
						(size 1.27 1.27)
					)
					(hide yes)
				)
			)
			(property "Description" ""
				(at 0 0 0)
				(effects
					(font
						(size 1.27 1.27)
					)
					(hide yes)
				)
			)
			(symbol "VCC_0_1"
				(polyline
					(pts
						(xy -0.762 1.27) (xy 0 2.54)
					)
					(stroke
						(width 0)
						(type default)
					)
					(fill
						(type none)
					)
				)
				(polyline
					(pts
						(xy 0 2.54) (xy 0.762 1.27)
					)
					(stroke
						(width 0)
						(type default)
					)
					(fill
						(type none)
					)
				)
				(polyline
					(pts
						(xy 0 0) (xy 0 2.54)
					)
					(stroke
						(width 0)
						(type default)
					)
					(fill
						(type none)
					)
				)
			)
			(symbol "VCC_1_1"
				(pin power_in line
					(at 0 0 90)
					(length 0)
					(hide yes)
					(name "VCC"
						(effects
							(font
								(size 1.27 1.27)
							)
						)
					)
					(number "1"
						(effects
							(font
								(size 1.27 1.27)
							)
						)
					)
				)
			)
		)
)
